G04 ================== begin FILE IDENTIFICATION RECORD ==================*
G04 Layout Name:  D:/<user>/Wistron_project/16315-1/gbr/16315-1.brd*
G04 Film Name:    L3*
G04 File Format:  Gerber RS274X*
G04 File Origin:  Cadence Allegro 16.5-S056*
G04 Origin Date:  Fri Jun 09 15:31:23 2017*
G04 *
G04 Layer:  VIA CLASS/L3*
G04 Layer:  PIN/L3*
G04 Layer:  ETCH/L3*
G04 Layer:  DRAWING FORMAT/LAYER_PCB_STORY*
G04 Layer:  DRAWING FORMAT/LAYER_L3*
G04 *
G04 Offset:    (0.00 0.00)*
G04 Mirror:    No*
G04 Mode:      Positive*
G04 Rotation:  0*
G04 FullContactRelief:  No*
G04 UndefLineWidth:     6.00*
G04 ================== end FILE IDENTIFICATION RECORD ====================*
%FSLAX35Y35*MOIN*%
%IR0*IPPOS*OFA0.00000B0.00000*MIA0B0*SFA1.00000B1.00000*%
%ADD12C,.03*%
%ADD11C,.022*%
%ADD13C,.042*%
%ADD14C,.034*%
%ADD10C,.028*%
%ADD15C,.048*%
%ADD16C,.01*%
%ADD17C,.02*%
%ADD18C,.006*%
%ADD19C,.0055*%
%ADD20C,.00525*%
%ADD22C,.06604*%
%ADD21C,.13704*%
G75*
%LPD*%
G75*
G36*
G01X3937Y3004D02*
G02X3004Y3937I0J933D01*
G01Y12071D01*
G02X3714Y12323I400J0D01*
G03X7898Y8796I11444J9330D01*
G01X8000Y8739D01*
Y8000D01*
X9537D01*
X9574Y7985D01*
G03X20778Y8000I5584J13669D01*
G01X393575D01*
Y55118D01*
G02X405512Y67055I11937J0D01*
G01X408351D01*
Y62059D01*
X405512D01*
G03X398571Y55118I0J-6941D01*
G01Y3937D01*
G02X397638Y3004I-933J0D01*
G01X3937D01*
G37*
G36*
G01X8000Y34568D02*
G03X3714Y30984I7158J-12914D01*
G02X3004Y31236I-310J253D01*
G01Y461899D01*
G02X3678Y462191I400J0D01*
G03X8000Y459248I11482J12217D01*
G01Y34568D01*
G37*
G36*
G01X758787Y1460504D02*
Y1378740D01*
G02X746850Y1366803I-11937J0D01*
G01X8000D01*
Y489570D01*
G03X3678Y486627I7160J-15160D01*
G02X3004Y486919I-274J292D01*
G01Y1370866D01*
G02X3937Y1371799I933J0D01*
G01X746850D01*
G03X753791Y1378740I0J6941D01*
G01Y1464567D01*
G02X754724Y1465500I933J0D01*
G01X783465D01*
G03X790406Y1472441I0J6941D01*
G01Y1654331D01*
G02X791339Y1655264I933J0D01*
G01X799262D01*
Y1650268D01*
X795402D01*
Y1472441D01*
G02X795364Y1471483I-11937J-6D01*
G03X794795Y1468683I1484J-1759D01*
G02X783465Y1460504I-11330J3758D01*
G01X758787D01*
G37*
G36*
G01X598551Y8000D02*
X783465D01*
G02X794689Y126I0J-11937D01*
G01X796727D01*
Y-4870D01*
X791339D01*
G02X790406Y-3937I0J933D01*
G03X783465Y3004I-6941J0D01*
G01X594488D01*
G02X593555Y3937I0J933D01*
G01Y55118D01*
G03X586614Y62059I-6941J0D01*
G01X585511D01*
Y67055D01*
X586614D01*
G02X598551Y55118I0J-11937D01*
G01Y8000D01*
G37*
G36*
G01X869146Y-16366D02*
X874142D01*
Y-144756D01*
X1173102D01*
Y-10956D01*
X1178098D01*
Y-148819D01*
G02X1177165Y-149752I-933J0D01*
G01X870079D01*
G02X869146Y-148819I0J933D01*
G01Y-16366D01*
G37*
G36*
G01X1003681Y1450890D02*
X994483Y1460088D01*
Y1484653D01*
X995330Y1485500D01*
X1080220D01*
X1082000Y1487280D01*
Y1609593D01*
X1086719Y1614312D01*
X1137982D01*
X1145983Y1606311D01*
Y1459747D01*
X1137126Y1450890D01*
X1003681D01*
G37*
G36*
G01X1080573Y1488483D02*
X1079590Y1487500D01*
X995968D01*
X994302Y1489166D01*
Y1534567D01*
X995775Y1536040D01*
X1078460D01*
X1080573Y1533927D01*
Y1488483D01*
G37*
G36*
G01X1120176Y712289D02*
X1115542Y709972D01*
X1115484Y709978D01*
G03X1111868Y706982I-327J-3286D01*
G01X1111852Y706800D01*
X1108620D01*
X1108604Y706982D01*
G03X1102026I-3289J-290D01*
G01X1102010Y706800D01*
X1082300D01*
X1079900Y709200D01*
Y750000D01*
X1079808Y750092D01*
Y752142D01*
X1082078Y754412D01*
X1179588D01*
X1182500Y751500D01*
Y709000D01*
X1180400Y706900D01*
X1122596D01*
G02X1122506Y707279I-1J200D01*
G01X1122646Y707349D01*
X1122704Y707343D01*
G03X1120206Y712338I327J3286D01*
G01X1120176Y712289D01*
G37*
G36*
G01X1567055Y55118D02*
Y8000D01*
X1889065D01*
G03X1900305I5620J13654D01*
G01X1926843D01*
Y1366803D01*
X1168110D01*
G02X1156666Y1375347I1J11937D01*
G01Y1411485D01*
X1156173Y1411977D01*
Y1468504D01*
G02X1168110Y1480441I11937J0D01*
G01X1212472D01*
Y1650268D01*
X1071589D01*
Y1655264D01*
X1216535D01*
G02X1217468Y1654331I0J-933D01*
G01Y1476378D01*
G02X1216535Y1475445I-933J0D01*
G01X1168110D01*
G03X1161169Y1468504I0J-6941D01*
G01Y1378740D01*
G03X1168110Y1371799I6941J0D01*
G01X1930906D01*
G02X1931839Y1370866I0J-933D01*
G01Y3937D01*
G02X1930906Y3004I-933J0D01*
G01X1562992D01*
G02X1562059Y3937I0J933D01*
G01Y55118D01*
G03X1555118Y62059I-6941J0D01*
G01X1554061D01*
Y67055D01*
X1555118D01*
G02X1567055Y55118I0J-11937D01*
G37*
G36*
G01X1362144Y56360D02*
X1371764Y65980D01*
Y66841D01*
G02X1374016Y67055I2250J-11723D01*
G01X1376944D01*
Y62059D01*
X1374016D01*
G03X1367075Y55118I0J-6941D01*
G01Y3937D01*
G02X1366142Y3004I-933J0D01*
G01X1185039D01*
G03X1178098Y-3937I0J-6941D01*
G01Y-9395D01*
X1173102D01*
Y-3937D01*
G02X1185039Y8000I11937J0D01*
G01X1362079D01*
Y55118D01*
G02X1362144Y56360I11937J-2D01*
G37*
%LPC*%
G75*
G36*
G01X1123366Y1586608D02*
G03X1122697I-334J-220D01*
G02Y1590558I-3012J1975D01*
G03X1123366I335J220D01*
G02Y1586608I3012J-1975D01*
G37*
G36*
G01X1105138D02*
G03X1104469I-334J-220D01*
G02Y1590558I-3012J1975D01*
G03X1105138I334J220D01*
G02Y1586608I3012J-1975D01*
G37*
G36*
G01X1095005Y1553378D02*
G03X1094469I-268J-297D01*
G02X1091290Y1556706I-1543J1708D01*
G03Y1557268I-284J281D01*
G02X1094469Y1560596I1636J1620D01*
G03X1095005I268J297D01*
G02X1098184Y1557268I1543J-1708D01*
G03Y1556706I284J-281D01*
G02X1095005Y1553378I-1636J-1620D01*
G37*
G36*
G01X1097575Y1533801D02*
G03Y1533239I284J-281D01*
G02X1094301I-1637J-1619D01*
G03Y1533801I-284J281D01*
G02X1097575I1637J1619D01*
G37*
G36*
G01X1092455D02*
G03Y1533239I284J-281D01*
G02X1089181I-1637J-1619D01*
G03Y1533801I-284J281D01*
G02X1092455I1637J1619D01*
G37*
G36*
G01X1075050Y1453527D02*
G03X1074458I-296J-269D01*
G02Y1456623I-1704J1548D01*
G03X1075050I296J269D01*
G02Y1453527I1704J-1548D01*
G37*
G36*
G01X1046358Y1456623D02*
G03X1046950I296J269D01*
G02Y1453527I1704J-1548D01*
G03X1046358I-296J-269D01*
G02Y1456623I-1704J1548D01*
G37*
G36*
G01X1018558D02*
G03X1019150I296J269D01*
G02Y1453527I1704J-1548D01*
G03X1018558I-296J-269D01*
G02Y1456623I-1704J1548D01*
G37*
G54D22*
X1097441Y710629D03*
X1115157Y714567D03*
X1123031Y718504D03*
G54D21*
X1110236Y725590D03*
%LPD*%
G75*
G54D10*
X24508Y5500D03*
X5500Y61492D03*
Y56492D03*
Y51492D03*
Y46492D03*
Y41492D03*
Y66492D03*
Y81492D03*
Y76492D03*
Y96492D03*
Y91492D03*
Y86492D03*
Y71492D03*
Y101492D03*
Y111492D03*
Y116492D03*
Y106492D03*
Y126492D03*
Y121492D03*
Y141492D03*
Y151492D03*
Y161492D03*
Y156492D03*
Y146492D03*
Y131492D03*
Y136492D03*
Y181492D03*
Y191492D03*
Y201492D03*
Y211492D03*
Y171492D03*
Y206492D03*
Y196492D03*
Y176492D03*
Y166492D03*
Y186492D03*
Y231492D03*
Y241492D03*
Y251492D03*
Y261492D03*
Y221492D03*
Y256492D03*
Y246492D03*
Y226492D03*
Y216492D03*
Y236492D03*
Y281492D03*
Y291492D03*
Y301492D03*
Y271492D03*
Y306492D03*
Y296492D03*
Y286492D03*
Y276492D03*
Y266492D03*
Y331492D03*
Y341492D03*
Y351492D03*
Y311492D03*
Y321492D03*
Y356492D03*
Y346492D03*
Y336492D03*
Y326492D03*
Y316492D03*
Y381492D03*
Y391492D03*
Y401492D03*
Y361492D03*
Y371492D03*
Y406492D03*
Y396492D03*
Y386492D03*
Y376492D03*
Y366492D03*
Y451492D03*
Y441492D03*
Y431492D03*
Y421492D03*
Y411492D03*
Y416492D03*
Y436492D03*
Y446492D03*
Y426492D03*
Y501492D03*
Y456492D03*
Y496492D03*
Y531492D03*
Y551492D03*
Y541492D03*
Y521492D03*
Y511492D03*
Y536492D03*
Y546492D03*
Y506492D03*
Y516492D03*
Y526492D03*
Y581492D03*
Y591492D03*
Y571492D03*
Y561492D03*
Y586492D03*
Y596492D03*
Y556492D03*
Y566492D03*
Y576492D03*
Y631492D03*
Y641492D03*
Y621492D03*
Y611492D03*
Y601492D03*
Y636492D03*
Y646492D03*
Y606492D03*
Y616492D03*
Y626492D03*
Y681492D03*
Y691492D03*
Y671492D03*
Y661492D03*
Y651492D03*
Y686492D03*
Y696492D03*
Y656492D03*
Y666492D03*
Y676492D03*
Y731492D03*
Y741492D03*
Y721492D03*
Y711492D03*
Y701492D03*
Y736492D03*
Y706492D03*
Y716492D03*
Y726492D03*
Y781492D03*
Y791492D03*
Y771492D03*
Y761492D03*
Y751492D03*
Y786492D03*
Y746492D03*
Y756492D03*
Y766492D03*
Y776492D03*
Y831492D03*
Y841492D03*
Y821492D03*
Y811492D03*
Y801492D03*
Y836492D03*
Y796492D03*
Y806492D03*
Y816492D03*
Y826492D03*
Y881492D03*
Y871492D03*
Y861492D03*
Y851492D03*
Y886492D03*
Y846492D03*
Y856492D03*
Y866492D03*
Y876492D03*
Y931492D03*
Y921492D03*
Y911492D03*
Y901492D03*
Y891492D03*
Y936492D03*
Y896492D03*
Y906492D03*
Y916492D03*
Y926492D03*
Y976492D03*
Y981492D03*
Y986492D03*
Y966492D03*
Y956492D03*
Y961492D03*
Y971492D03*
Y951492D03*
Y941492D03*
Y946492D03*
Y991492D03*
Y996492D03*
Y1001492D03*
Y1006492D03*
Y1026492D03*
Y1016492D03*
Y1011492D03*
Y1021492D03*
Y1031492D03*
Y1036492D03*
Y1066492D03*
Y1056492D03*
Y1046492D03*
Y1041492D03*
Y1051492D03*
Y1061492D03*
Y1071492D03*
Y1081492D03*
Y1076492D03*
Y1121492D03*
Y1131492D03*
Y1111492D03*
Y1101492D03*
Y1091492D03*
Y1086492D03*
Y1096492D03*
Y1106492D03*
Y1116492D03*
Y1126492D03*
Y1171492D03*
Y1161492D03*
Y1151492D03*
Y1141492D03*
Y1136492D03*
Y1146492D03*
Y1156492D03*
Y1166492D03*
Y1176492D03*
Y1221492D03*
Y1211492D03*
Y1201492D03*
Y1191492D03*
Y1181492D03*
Y1186492D03*
Y1196492D03*
Y1206492D03*
Y1216492D03*
Y1226492D03*
Y1271492D03*
Y1261492D03*
Y1251492D03*
Y1241492D03*
Y1231492D03*
Y1236492D03*
Y1246492D03*
Y1256492D03*
Y1266492D03*
Y1276492D03*
Y1321492D03*
Y1311492D03*
Y1301492D03*
Y1291492D03*
Y1281492D03*
Y1286492D03*
Y1296492D03*
Y1306492D03*
Y1316492D03*
X8983Y1368303D03*
X13983D03*
X18983D03*
X23983D03*
X5500Y1361492D03*
Y1351492D03*
Y1341492D03*
Y1331492D03*
Y1336492D03*
Y1346492D03*
Y1356492D03*
Y1326492D03*
X29508Y5500D03*
X39508D03*
X34508D03*
X44508D03*
X64508D03*
X69508D03*
X54508D03*
X49508D03*
X59508D03*
X28983Y1368303D03*
X33983D03*
X38983D03*
X43983D03*
X48983D03*
X53983D03*
X58983D03*
X63983D03*
X68983D03*
X114508Y5500D03*
X119508D03*
X104508D03*
X94508D03*
X84508D03*
X74508D03*
X79508D03*
X89508D03*
X99508D03*
X109508D03*
X73983Y1368303D03*
X78983D03*
X83983D03*
X88983D03*
X93983D03*
X98983D03*
X107374Y1369303D03*
X112374D03*
X117374D03*
X134508Y5500D03*
X124508D03*
X129508D03*
X169508D03*
X159508D03*
X149508D03*
X139508D03*
X154508D03*
X164508D03*
X144508D03*
X122374Y1369303D03*
X127374D03*
X132374D03*
X137374D03*
X142374D03*
X147374D03*
X152374D03*
X157374D03*
X162374D03*
X167374D03*
X209508Y5500D03*
X199508D03*
X189508D03*
X179508D03*
X204508D03*
X214508D03*
X174508D03*
X184508D03*
X194508D03*
X172374Y1369303D03*
X177374D03*
X182374D03*
X187374D03*
X192374D03*
X197374D03*
X202374D03*
X207374D03*
X212374D03*
X217374D03*
X259508Y5500D03*
X249508D03*
X239508D03*
X229508D03*
X219508D03*
X224508D03*
X234508D03*
X244508D03*
X254508D03*
X264508D03*
X222374Y1369303D03*
X227374D03*
X232374D03*
X237374D03*
X242374D03*
X247374D03*
X252374D03*
X257374D03*
X262374D03*
X309508Y5500D03*
X299508D03*
X289508D03*
X279508D03*
X269508D03*
X304508D03*
X314508D03*
X274508D03*
X284508D03*
X294508D03*
X267374Y1369303D03*
X272374D03*
X277374D03*
X282374D03*
X287374D03*
X292374D03*
X297374D03*
X302374D03*
X307374D03*
X312374D03*
X359508Y5500D03*
X349508D03*
X339508D03*
X329508D03*
X319508D03*
X324508D03*
X334508D03*
X344508D03*
X354508D03*
X333983Y1368303D03*
X338983D03*
X343983D03*
X348983D03*
X353983D03*
X358983D03*
X363983D03*
X317374Y1369303D03*
X322374D03*
X327374D03*
X395075Y18639D03*
Y13639D03*
X389508Y5500D03*
X379508D03*
X369508D03*
X364508D03*
X374508D03*
X384508D03*
X394508D03*
X395075Y43639D03*
Y38639D03*
Y33639D03*
Y28639D03*
Y23639D03*
X399000Y62000D03*
X396000Y55500D03*
X396075Y50248D03*
X368983Y1368303D03*
X373983D03*
X378983D03*
X383983D03*
X388983D03*
X393983D03*
X398983D03*
X403983D03*
X408983D03*
X413983D03*
X418983D03*
X423983D03*
X428983D03*
X433983D03*
X438983D03*
X443983D03*
X448983D03*
X453983D03*
X458983D03*
X463983D03*
X468983D03*
X473983D03*
X478983D03*
X483983D03*
X488983D03*
X493983D03*
X498983D03*
X503983D03*
X508983D03*
X517374Y1369303D03*
X522374D03*
X527374D03*
X532374D03*
X537374D03*
X542374D03*
X547374D03*
X552374D03*
X557374D03*
X597051Y7699D03*
Y12699D03*
Y17699D03*
X604146Y5500D03*
X597051Y22699D03*
Y27699D03*
Y32699D03*
Y37699D03*
Y42699D03*
X589000Y64000D03*
X594000Y61500D03*
X596000Y56500D03*
X596051Y51090D03*
X567374Y1369303D03*
X572374D03*
X577374D03*
X582374D03*
X587374D03*
X592374D03*
X597374D03*
X602374D03*
X562374D03*
X609146Y5500D03*
X619146D03*
X614146D03*
X629146D03*
X639146D03*
X649146D03*
X654146D03*
X644146D03*
X634146D03*
X624146D03*
X617374Y1369303D03*
X622374D03*
X627374D03*
X632374D03*
X637374D03*
X642374D03*
X647374D03*
X652374D03*
X607374D03*
X612374D03*
X679146Y5500D03*
X689146D03*
X694146D03*
X684146D03*
X659146D03*
X669146D03*
X664146D03*
X674146D03*
X699146D03*
X667374Y1369303D03*
X672374D03*
X677374D03*
X682374D03*
X687374D03*
X692374D03*
X697374D03*
X702374D03*
X657374D03*
X662374D03*
X749146Y5500D03*
X709146D03*
X719146D03*
X729146D03*
X739146D03*
X744146D03*
X734146D03*
X724146D03*
X714146D03*
X704146D03*
X747374Y1369303D03*
X742374D03*
X717374D03*
X722374D03*
X727374D03*
X732374D03*
X737374D03*
X707374D03*
X712374D03*
X795969Y-1374D03*
X759146Y5500D03*
X769146D03*
X774146D03*
X764146D03*
X754146D03*
X779146D03*
X755500Y1374500D03*
X752500Y1370500D03*
X757287Y1380873D03*
Y1385873D03*
Y1390873D03*
Y1395873D03*
Y1400873D03*
Y1405873D03*
Y1410873D03*
Y1415873D03*
Y1420873D03*
Y1425873D03*
Y1430873D03*
Y1435873D03*
Y1440873D03*
Y1445873D03*
X766156Y1462004D03*
X771156D03*
X790500Y1466500D03*
X786000Y1463500D03*
X756287Y1459264D03*
Y1454264D03*
X779547Y1463004D03*
X792902Y1477964D03*
Y1487964D03*
Y1497964D03*
Y1507964D03*
Y1517964D03*
Y1512964D03*
Y1472964D03*
Y1482964D03*
Y1492964D03*
Y1502964D03*
Y1562964D03*
Y1527964D03*
Y1537964D03*
Y1547964D03*
Y1557964D03*
Y1567964D03*
Y1522964D03*
Y1532964D03*
Y1542964D03*
Y1552964D03*
Y1612964D03*
Y1602964D03*
Y1592964D03*
Y1582964D03*
Y1572964D03*
Y1577964D03*
Y1587964D03*
Y1597964D03*
Y1607964D03*
X797902Y1652964D03*
X792902D03*
Y1642964D03*
Y1632964D03*
Y1622964D03*
Y1627964D03*
Y1637964D03*
Y1647964D03*
Y1617964D03*
X872642Y-140575D03*
Y-135575D03*
Y-130575D03*
Y-125575D03*
X890264Y-147256D03*
X880264D03*
X875264D03*
X885264D03*
X895264D03*
X872642Y-80575D03*
Y-120575D03*
Y-115575D03*
Y-110575D03*
Y-105575D03*
Y-100575D03*
Y-95575D03*
Y-90575D03*
Y-85575D03*
Y-30575D03*
Y-35575D03*
Y-40575D03*
Y-45575D03*
Y-50575D03*
Y-55575D03*
Y-60575D03*
Y-65575D03*
Y-70575D03*
Y-75575D03*
Y-20575D03*
Y-25575D03*
X940264Y-147256D03*
X930264D03*
X925264D03*
X935264D03*
X920264D03*
X910264D03*
X900264D03*
X905264D03*
X915264D03*
X960264D03*
X950264D03*
X955264D03*
X965264D03*
X945264D03*
X990264D03*
X980264D03*
X970264D03*
X975264D03*
X985264D03*
X1010264D03*
X1000264D03*
X1005264D03*
X1015264D03*
X995264D03*
X1040264D03*
X1030264D03*
X1020264D03*
X1025264D03*
X1035264D03*
X1060264D03*
X1050264D03*
X1055264D03*
X1065264D03*
X1045264D03*
X1080264D03*
X1070264D03*
X1075264D03*
X1085264D03*
X1078098Y1652768D03*
X1073098D03*
X1083098D03*
X1088098D03*
X1110264Y-147256D03*
X1100264D03*
X1090264D03*
X1105264D03*
X1095264D03*
X1130264D03*
X1120264D03*
X1115264D03*
X1125264D03*
X1135264D03*
X1093098Y1652768D03*
X1133098D03*
X1123098D03*
X1113098D03*
X1103098D03*
X1108098D03*
X1118098D03*
X1128098D03*
X1098098D03*
X1170264Y-147256D03*
X1155264D03*
X1175602Y-137594D03*
Y-127594D03*
X1160264Y-147256D03*
X1150264D03*
X1140264D03*
X1145264D03*
X1175602Y-132594D03*
Y-142594D03*
X1165264Y-147256D03*
X1175602Y-117594D03*
Y-107594D03*
Y-97594D03*
Y-87594D03*
Y-77594D03*
Y-82594D03*
Y-92594D03*
Y-102594D03*
Y-112594D03*
Y-122594D03*
Y-67594D03*
Y-57594D03*
Y-47594D03*
Y-37594D03*
Y-32594D03*
Y-42594D03*
Y-52594D03*
Y-62594D03*
Y-72594D03*
Y-17594D03*
Y-27594D03*
X1180500Y4000D03*
X1176500Y-500D03*
X1175602Y-22594D03*
Y-12594D03*
Y-7594D03*
X1162000Y1371500D03*
X1169783Y1369303D03*
X1179783D03*
X1174783D03*
X1184783D03*
X1158673Y1417067D03*
Y1407067D03*
Y1397067D03*
Y1387067D03*
Y1377067D03*
Y1412067D03*
Y1402067D03*
Y1392067D03*
Y1382067D03*
Y1422067D03*
Y1442067D03*
Y1452067D03*
X1158500Y1468500D03*
X1158673Y1457067D03*
Y1447067D03*
Y1437067D03*
Y1427067D03*
Y1462067D03*
Y1432067D03*
X1161000Y1474500D03*
X1166673Y1477941D03*
X1171673D03*
X1181673D03*
X1176673D03*
X1143098Y1652768D03*
X1183098D03*
X1173098D03*
X1163098D03*
X1153098D03*
X1158098D03*
X1168098D03*
X1178098D03*
X1138098D03*
X1148098D03*
X1191382Y5500D03*
X1196382D03*
X1186382D03*
X1201382D03*
X1211382D03*
X1221382D03*
X1231382D03*
X1226382D03*
X1216382D03*
X1206382D03*
X1199783Y1369303D03*
X1209783D03*
X1219783D03*
X1229783D03*
X1189783D03*
X1224783D03*
X1214783D03*
X1204783D03*
X1194783D03*
X1191673Y1477941D03*
X1201673D03*
X1214972Y1482642D03*
Y1517642D03*
Y1487642D03*
Y1497642D03*
Y1507642D03*
Y1512642D03*
Y1502642D03*
Y1492642D03*
X1206673Y1477941D03*
X1196673D03*
X1186673D03*
X1211673D03*
X1214972Y1567642D03*
Y1527642D03*
Y1537642D03*
Y1547642D03*
Y1557642D03*
Y1562642D03*
Y1552642D03*
Y1542642D03*
Y1532642D03*
Y1522642D03*
Y1577642D03*
Y1587642D03*
Y1597642D03*
Y1607642D03*
Y1612642D03*
Y1602642D03*
Y1592642D03*
Y1582642D03*
Y1572642D03*
Y1617642D03*
Y1627642D03*
Y1637642D03*
X1213098Y1652768D03*
X1193098D03*
X1203098D03*
X1208098D03*
X1214972Y1642642D03*
Y1632642D03*
X1188098Y1652768D03*
X1198098D03*
X1214972Y1622642D03*
Y1647642D03*
X1251382Y5500D03*
X1261382D03*
X1271382D03*
X1281382D03*
X1276382D03*
X1266382D03*
X1256382D03*
X1241382D03*
X1246382D03*
X1236382D03*
X1249783Y1369303D03*
X1259783D03*
X1269783D03*
X1279783D03*
X1239783D03*
X1274783D03*
X1264783D03*
X1254783D03*
X1234783D03*
X1244783D03*
X1301382Y5500D03*
X1311382D03*
X1296382D03*
X1316382D03*
X1306382D03*
X1291382D03*
X1286382D03*
X1326382D03*
X1321382D03*
X1299783Y1369303D03*
X1309783D03*
X1319783D03*
X1329783D03*
X1289783D03*
X1324783D03*
X1314783D03*
X1304783D03*
X1294783D03*
X1284783D03*
X1363579Y19821D03*
Y14821D03*
Y9821D03*
X1351382Y5500D03*
X1356382D03*
X1346382D03*
X1336382D03*
X1341382D03*
X1331382D03*
X1363579Y44821D03*
Y39821D03*
Y34821D03*
Y29821D03*
Y24821D03*
X1374000Y64500D03*
X1363579Y51618D03*
X1349783Y1369303D03*
X1359783D03*
X1369783D03*
X1339783D03*
X1374783D03*
X1364783D03*
X1354783D03*
X1344783D03*
X1334783D03*
X1399783D03*
X1409783D03*
X1419783D03*
X1379783D03*
X1389783D03*
X1404783D03*
X1414783D03*
X1424783D03*
X1394783D03*
X1384783D03*
X1449783D03*
X1459783D03*
X1469783D03*
X1429783D03*
X1439783D03*
X1444783D03*
X1454783D03*
X1464783D03*
X1474783D03*
X1434783D03*
X1499783D03*
X1509783D03*
X1519783D03*
X1479783D03*
X1489783D03*
X1494783D03*
X1484783D03*
X1504783D03*
X1514783D03*
X1565555Y16517D03*
X1568030Y5500D03*
X1565555Y21517D03*
Y26517D03*
Y31517D03*
Y36517D03*
Y41517D03*
X1557000Y64500D03*
X1561500Y62000D03*
X1564000Y57500D03*
X1564555Y52124D03*
X1549783Y1369303D03*
X1559783D03*
X1569783D03*
X1529783D03*
X1539783D03*
X1524783D03*
X1534783D03*
X1544783D03*
X1554783D03*
X1564783D03*
X1603030Y5500D03*
X1613030D03*
X1573030D03*
X1583030D03*
X1593030D03*
X1618030D03*
X1608030D03*
X1598030D03*
X1588030D03*
X1578030D03*
X1614783Y1369303D03*
X1604783D03*
X1599783D03*
X1609783D03*
X1619783D03*
X1579783D03*
X1589783D03*
X1574783D03*
X1584783D03*
X1594783D03*
X1653030Y5500D03*
X1663030D03*
X1623030D03*
X1633030D03*
X1643030D03*
X1668030D03*
X1658030D03*
X1648030D03*
X1638030D03*
X1628030D03*
X1664783Y1369303D03*
X1654783D03*
X1644783D03*
X1634783D03*
X1624783D03*
X1649783D03*
X1659783D03*
X1629783D03*
X1639783D03*
X1703030Y5500D03*
X1713030D03*
X1673030D03*
X1683030D03*
X1693030D03*
X1718030D03*
X1708030D03*
X1698030D03*
X1688030D03*
X1678030D03*
X1714783Y1369303D03*
X1704783D03*
X1694783D03*
X1684783D03*
X1674783D03*
X1699783D03*
X1709783D03*
X1669783D03*
X1679783D03*
X1689783D03*
X1753030Y5500D03*
X1763030D03*
X1723030D03*
X1733030D03*
X1743030D03*
X1758030D03*
X1748030D03*
X1738030D03*
X1728030D03*
X1764783Y1369303D03*
X1754783D03*
X1744783D03*
X1734783D03*
X1724783D03*
X1749783D03*
X1759783D03*
X1719783D03*
X1729783D03*
X1739783D03*
X1778030Y5500D03*
X1793030D03*
X1803030D03*
X1813030D03*
X1808030D03*
X1798030D03*
X1783030D03*
X1788030D03*
X1773030D03*
X1768030D03*
X1804783Y1369303D03*
X1794783D03*
X1784783D03*
X1774783D03*
X1799783D03*
X1809783D03*
X1769783D03*
X1779783D03*
X1789783D03*
X1843030Y5500D03*
X1853030D03*
X1863030D03*
X1838030D03*
X1858030D03*
X1848030D03*
X1823030D03*
X1833030D03*
X1828030D03*
X1818030D03*
X1862652Y846508D03*
X1854783Y1369303D03*
X1844783D03*
X1834783D03*
X1824783D03*
X1814783D03*
X1849783D03*
X1859783D03*
X1819783D03*
X1829783D03*
X1839783D03*
X1878030Y5500D03*
X1883030D03*
X1873030D03*
X1868030D03*
X1909030D03*
X1888030D03*
X1904783Y1369303D03*
X1894783D03*
X1884783D03*
X1874783D03*
X1864783D03*
X1899783D03*
X1909783D03*
X1869783D03*
X1879783D03*
X1889783D03*
X1929343Y16525D03*
Y11525D03*
Y6525D03*
X1914030Y5500D03*
X1919030D03*
X1924030D03*
X1929343Y46525D03*
Y41525D03*
Y36525D03*
Y31525D03*
Y26525D03*
Y21525D03*
Y66525D03*
Y61525D03*
Y56525D03*
Y51525D03*
Y116525D03*
Y111525D03*
Y106525D03*
Y101525D03*
Y96525D03*
Y91525D03*
Y86525D03*
Y81525D03*
Y76525D03*
Y71525D03*
Y121525D03*
Y126525D03*
Y136525D03*
Y146525D03*
Y156525D03*
Y161525D03*
Y151525D03*
Y141525D03*
Y131525D03*
Y176525D03*
Y186525D03*
Y196525D03*
Y206525D03*
Y166525D03*
Y211525D03*
Y201525D03*
Y191525D03*
Y181525D03*
Y171525D03*
Y226525D03*
Y236525D03*
Y246525D03*
Y256525D03*
Y216525D03*
Y261525D03*
Y251525D03*
Y241525D03*
Y231525D03*
Y221525D03*
Y276525D03*
Y286525D03*
Y296525D03*
Y306525D03*
Y266525D03*
Y301525D03*
Y291525D03*
Y281525D03*
Y271525D03*
Y326525D03*
Y336525D03*
Y346525D03*
Y356525D03*
Y316525D03*
Y351525D03*
Y341525D03*
Y331525D03*
Y321525D03*
Y311525D03*
Y376525D03*
Y386525D03*
Y396525D03*
Y406525D03*
Y366525D03*
Y401525D03*
Y391525D03*
Y381525D03*
Y371525D03*
Y361525D03*
Y426525D03*
Y436525D03*
Y446525D03*
Y416525D03*
Y451525D03*
Y441525D03*
Y431525D03*
Y421525D03*
Y411525D03*
Y476525D03*
Y486525D03*
Y496525D03*
Y456525D03*
Y466525D03*
Y501525D03*
Y491525D03*
Y481525D03*
Y471525D03*
Y461525D03*
Y526525D03*
Y536525D03*
Y546525D03*
Y506525D03*
Y516525D03*
Y551525D03*
Y541525D03*
Y531525D03*
Y521525D03*
Y511525D03*
Y576525D03*
Y586525D03*
Y596525D03*
Y556525D03*
Y566525D03*
Y591525D03*
Y581525D03*
Y571525D03*
Y561525D03*
Y626525D03*
Y636525D03*
Y646525D03*
Y606525D03*
Y616525D03*
Y641525D03*
Y631525D03*
Y621525D03*
Y611525D03*
Y601525D03*
Y676525D03*
Y686525D03*
Y696525D03*
Y656525D03*
Y666525D03*
Y691525D03*
Y681525D03*
Y671525D03*
Y661525D03*
Y651525D03*
Y726525D03*
Y736525D03*
Y706525D03*
Y716525D03*
Y741525D03*
Y731525D03*
Y721525D03*
Y711525D03*
Y701525D03*
Y776525D03*
Y786525D03*
Y746525D03*
Y756525D03*
Y766525D03*
Y791525D03*
Y781525D03*
Y771525D03*
Y761525D03*
Y751525D03*
Y826525D03*
Y836525D03*
Y796525D03*
Y806525D03*
Y816525D03*
Y841525D03*
Y831525D03*
Y821525D03*
Y811525D03*
Y801525D03*
Y876525D03*
Y886525D03*
Y846525D03*
Y856525D03*
Y866525D03*
Y881525D03*
Y871525D03*
Y861525D03*
Y851525D03*
Y926525D03*
Y896525D03*
Y906525D03*
Y916525D03*
Y931525D03*
Y921525D03*
Y911525D03*
Y901525D03*
Y891525D03*
Y936525D03*
Y973863D03*
Y978863D03*
Y983863D03*
Y951525D03*
Y956525D03*
Y961525D03*
Y966525D03*
Y946525D03*
Y941525D03*
Y988863D03*
Y993863D03*
Y998863D03*
Y1003863D03*
Y1008863D03*
Y1033863D03*
Y1028863D03*
Y1023863D03*
Y1018863D03*
Y1013863D03*
Y1073863D03*
Y1083863D03*
Y1043863D03*
Y1053863D03*
Y1063863D03*
Y1078863D03*
Y1068863D03*
Y1058863D03*
Y1048863D03*
Y1038863D03*
Y1123863D03*
Y1093863D03*
Y1103863D03*
Y1113863D03*
Y1128863D03*
Y1118863D03*
Y1108863D03*
Y1098863D03*
Y1088863D03*
Y1173863D03*
Y1133863D03*
Y1143863D03*
Y1153863D03*
Y1163863D03*
Y1178863D03*
Y1168863D03*
Y1158863D03*
Y1148863D03*
Y1138863D03*
Y1223863D03*
Y1183863D03*
Y1193863D03*
Y1203863D03*
Y1213863D03*
Y1228863D03*
Y1218863D03*
Y1208863D03*
Y1198863D03*
Y1188863D03*
Y1273863D03*
Y1233863D03*
Y1243863D03*
Y1253863D03*
Y1263863D03*
Y1268863D03*
Y1258863D03*
Y1248863D03*
Y1238863D03*
Y1323863D03*
Y1283863D03*
Y1293863D03*
Y1303863D03*
Y1313863D03*
Y1318863D03*
Y1308863D03*
Y1298863D03*
Y1288863D03*
Y1278863D03*
Y1333863D03*
Y1343863D03*
Y1353863D03*
X1924783Y1369303D03*
X1914783D03*
X1919783D03*
X1929343Y1358863D03*
Y1348863D03*
Y1338863D03*
Y1328863D03*
Y1363863D03*
G54D20*
G01X1041280Y1121500D02*
Y1132985D01*
X1025758Y1148507D01*
X989096D01*
X982103Y1155500D01*
X965262D01*
X959791Y1160971D01*
X784429D01*
X773801Y1171599D01*
X762361D01*
X751310Y1182650D01*
X751210D01*
X746256Y1187604D01*
X648653D01*
X644448Y1183399D01*
X600591D01*
X597365Y1180173D01*
X489127D01*
X485800Y1183500D01*
X478833D01*
X475508Y1180175D01*
X462788D01*
X462786Y1180173D01*
X460962D01*
X460960Y1180175D01*
X397175D01*
X395000Y1178000D01*
X35900D01*
X34250Y1176350D01*
X19712D01*
G01X1036160Y1095500D02*
X1035160Y1096500D01*
X1009983D01*
X974156Y1132327D01*
X817915D01*
X796892Y1111304D01*
X727088D01*
X725988Y1112404D01*
X696896D01*
X681875Y1127425D01*
X545927D01*
X542848Y1124346D01*
X503675D01*
X495302Y1115973D01*
X264193D01*
X248766Y1131400D01*
X39325D01*
G01X1041280Y1113900D02*
X1033600Y1121580D01*
Y1134441D01*
X1023934Y1144107D01*
X987272D01*
X980279Y1151100D01*
X963438D01*
X957967Y1156571D01*
X782605D01*
X771977Y1167199D01*
X760437D01*
X749436Y1178200D01*
X635763D01*
X633637Y1176074D01*
X599490D01*
X594273Y1170857D01*
X512774D01*
X507860Y1175771D01*
X440894D01*
X436299Y1171176D01*
X407650D01*
X405526Y1173300D01*
X379050D01*
X373450Y1167700D01*
X152370D01*
X146470Y1173600D01*
X36848D01*
G01X1115105Y1245296D02*
X1111409Y1241600D01*
X1090605D01*
X1070105Y1262100D01*
X962662D01*
X947500Y1246938D01*
X749426D01*
X726488Y1224000D01*
X31500D01*
G01X39425Y1226200D02*
X725576D01*
X748514Y1249138D01*
X946038D01*
X961200Y1264300D01*
X1073900D01*
X1089200Y1249000D01*
X1105889D01*
X1109593Y1245296D01*
G01X37225Y1230100D02*
X39825Y1232700D01*
X267900D01*
X275636Y1240436D01*
X651136D01*
X688511Y1277811D01*
X731500D01*
G01X1115105Y1287816D02*
X1111421Y1291500D01*
X690674D01*
X646874Y1335300D01*
X563194D01*
X561094Y1333200D01*
X560686D01*
X560674Y1333188D01*
X296964D01*
X296913Y1333137D01*
X295287D01*
X295224Y1333200D01*
X287300D01*
X278100Y1342400D01*
X51552D01*
X45518Y1336366D01*
G01X41381Y1335567D02*
X53273Y1347459D01*
X507004D01*
X512771Y1353226D01*
X546541D01*
X551015Y1357700D01*
X656855D01*
X667055Y1347500D01*
X822100D01*
X863187Y1388587D01*
X893593D01*
X893606Y1388600D01*
X894400D01*
X895900Y1390100D01*
G01X920770Y1067389D02*
X919355Y1068804D01*
X710956D01*
X683587Y1096173D01*
X658069D01*
X629433Y1067537D01*
X466245D01*
X465234Y1066526D01*
X433586D01*
X432212Y1067900D01*
X314500D01*
X311800Y1070600D01*
X297700D01*
X295000Y1067900D01*
X272688D01*
X270588Y1065800D01*
X237700D01*
X223600Y1079900D01*
X188600D01*
X181600Y1086900D01*
X148400D01*
G01X728174Y1275611D02*
X689511D01*
X651636Y1237736D01*
X278636D01*
X270200Y1229300D01*
X148800D01*
X148300Y1228800D01*
G01X163500Y1345200D02*
X163559Y1345259D01*
X507916D01*
X513683Y1351026D01*
X547454D01*
X548171Y1351743D01*
Y1351744D01*
X551927Y1355500D01*
X655943D01*
X666143Y1345300D01*
X823200D01*
X863900Y1386000D01*
X896200D01*
G01X903368Y934568D02*
X901442D01*
X897310Y938700D01*
X880888D01*
X874099Y945489D01*
X771375D01*
X758964Y957900D01*
X705736D01*
X670636Y922800D01*
X200300D01*
X199900Y923200D01*
G01X1036160Y1091700D02*
X1011671D01*
X973244Y1130127D01*
X818827D01*
X797804Y1109104D01*
X726176D01*
X725076Y1110204D01*
X694896D01*
X682258Y1122842D01*
X606788D01*
X594719Y1110773D01*
X445715D01*
X445388Y1111100D01*
X198896D01*
X195100Y1107304D01*
Y1096800D01*
G01X223100Y920600D02*
X671548D01*
X706648Y955700D01*
X758052D01*
X770463Y943289D01*
X873187D01*
X879976Y936500D01*
X896397D01*
X901756Y931141D01*
X904594D01*
G01X912994Y971921D02*
X904373Y963300D01*
X891100D01*
X870500Y983900D01*
X284700D01*
X281800Y986800D01*
X269488D01*
X268888Y986200D01*
X239600D01*
X239000Y985600D01*
G01X910397Y979189D02*
X908107Y976899D01*
Y971900D01*
X902007Y965800D01*
X893400D01*
X867680Y991520D01*
X863590D01*
X861811Y993299D01*
X678427D01*
X676828Y991700D01*
X558412D01*
X556675Y993437D01*
X255437D01*
X252100Y990100D01*
G01X244600Y1004600D02*
X246800Y1002400D01*
X443588D01*
X444288Y1003100D01*
X571288D01*
X571388Y1003200D01*
X672732D01*
X674031Y1004499D01*
X785770D01*
X785771Y1004500D01*
X898200D01*
X904144Y998556D01*
X904601D01*
G01X910040Y1006613D02*
X909953Y1006700D01*
X784859D01*
X784858Y1006699D01*
X673155D01*
X672156Y1005700D01*
X261100D01*
G01X1041280Y1095500D02*
Y1096620D01*
X1037000Y1100900D01*
X1011807D01*
X975980Y1136727D01*
X816091D01*
X797268Y1117904D01*
X697620D01*
X683699Y1131825D01*
X446614D01*
X435289Y1120500D01*
X264864D01*
G01X465157Y114764D02*
X461700Y118221D01*
Y122747D01*
X456047Y128400D01*
X429647D01*
X369747Y68500D01*
X335400D01*
X328600Y75300D01*
X304800D01*
X303000Y73500D01*
G01X887500Y378495D02*
X725074D01*
X680694Y422875D01*
X449075D01*
X446700Y420500D01*
X293598D01*
X291601Y418503D01*
G01X268100Y982300D02*
X269700Y983900D01*
X281588D01*
X283788Y981700D01*
X869008D01*
X890008Y960700D01*
X928293D01*
X938445Y970852D01*
X951312D01*
X951313Y970851D01*
X970249D01*
X979020Y962080D01*
Y960000D01*
G01X273300Y981700D02*
X280676D01*
X283176Y979200D01*
X288200D01*
X291600Y975800D01*
X871796D01*
X889096Y958500D01*
X929205D01*
X939357Y968652D01*
X950400D01*
X950401Y968651D01*
X969349D01*
X976100Y961900D01*
Y959120D01*
X979020Y956200D01*
G01X280800Y1011900D02*
X402897D01*
X403660Y1012663D01*
X433100D01*
X441624Y1021187D01*
X685777D01*
X685778Y1021188D01*
X762912D01*
X765638Y1018462D01*
X767024D01*
X767025Y1018463D01*
X779326D01*
X779826Y1017963D01*
X915473D01*
X921536Y1011900D01*
X1004040D01*
X1008300Y1007640D01*
X1013700D01*
G01X974020Y1022400D02*
X971800Y1024620D01*
Y1027516D01*
X961110Y1038206D01*
X912912D01*
X909748Y1035042D01*
X762318D01*
X760924Y1033648D01*
X293890D01*
X293242Y1033000D01*
X281200D01*
G01X921149Y1062424D02*
X916969Y1066604D01*
X710044D01*
X682675Y1093973D01*
X658981D01*
X630344Y1065336D01*
X467156D01*
X465620Y1063800D01*
X433200D01*
X431300Y1065700D01*
X273600D01*
X271100Y1063200D01*
G01X974020Y1026200D02*
Y1028408D01*
X962022Y1040406D01*
X911223D01*
X909677Y1038860D01*
Y1038859D01*
X908060Y1037242D01*
X761406D01*
X760364Y1036200D01*
X294288D01*
X293744Y1036744D01*
X281500D01*
G01X276100Y1229100D02*
X282536Y1235536D01*
X652836D01*
X690099Y1272799D01*
X725678D01*
G01X1016672Y1338228D02*
X1012444Y1334000D01*
X877400D01*
X840550Y1297150D01*
X692539D01*
X649002Y1340687D01*
X561066D01*
X558592Y1338213D01*
X521387D01*
X520104Y1339496D01*
X296104D01*
X295900Y1339700D01*
G01X1016835Y1323916D02*
X1010426Y1330325D01*
X879725D01*
X864073Y1314673D01*
Y1314672D01*
X843201Y1293800D01*
X691151D01*
X647614Y1337337D01*
X562454D01*
X559980Y1334863D01*
X296337D01*
X296100Y1335100D01*
G01X1079500Y1276100D02*
X753006D01*
X739906Y1289200D01*
X689862D01*
X645888Y1333174D01*
X564180D01*
X561706Y1330700D01*
X282300D01*
X279900Y1328300D01*
G01X283700D02*
X562418D01*
X565092Y1330974D01*
X644976D01*
X688950Y1287000D01*
X738994D01*
X752094Y1273900D01*
X1083105D01*
X1093605Y1284400D01*
X1115371D01*
X1119042Y1280729D01*
G01X286100Y1349659D02*
X506092D01*
X511859Y1355426D01*
X545426D01*
X549900Y1359900D01*
X657767D01*
X667967Y1349700D01*
X821188D01*
X861988Y1390500D01*
X892800D01*
X896100Y1393800D01*
G01X1016600Y1332000D02*
X879031D01*
X842506Y1295475D01*
X691845D01*
X648308Y1339012D01*
X561760D01*
X559286Y1336538D01*
X299162D01*
X298333Y1337367D01*
X292600D01*
G01X881549Y326304D02*
X873430Y334423D01*
X790787D01*
X790657Y334293D01*
X775144D01*
X739545Y298694D01*
Y235191D01*
X719591Y215237D01*
Y193029D01*
X669706Y143144D01*
X582938D01*
X581958Y144124D01*
Y144125D01*
X579997Y146086D01*
Y146087D01*
X577535Y148549D01*
X502341D01*
X492456Y138664D01*
X412319D01*
X359200Y85545D01*
Y73418D01*
X361776Y70842D01*
G01X1338215Y107586D02*
X1336879Y106250D01*
X1330066D01*
X1323968Y100152D01*
X1307998D01*
X1302179Y94333D01*
X1223833D01*
X1212500Y83000D01*
Y50398D01*
X1205028Y42926D01*
X1157026D01*
X1123300Y9200D01*
X1042368D01*
X988602Y62966D01*
Y353686D01*
X972110Y370178D01*
X908007D01*
X894750Y356921D01*
X885771D01*
X884806Y357886D01*
X723994D01*
X657885Y291777D01*
Y241218D01*
X642714Y226047D01*
X456244D01*
X349701Y119504D01*
X349628D01*
X348478Y118354D01*
Y118281D01*
X345133Y114936D01*
Y114133D01*
X335081Y104081D01*
G01X339219Y95188D02*
X344265Y100234D01*
X352899D01*
X414809Y162144D01*
X626605D01*
X685929Y221468D01*
Y293751D01*
X739009Y346831D01*
X744738D01*
X745705Y345864D01*
X903245D01*
X920205Y362824D01*
X968394D01*
X981902Y349316D01*
Y50985D01*
X1031130Y1757D01*
X1126046D01*
X1160440Y36151D01*
X1207729D01*
X1219200Y47622D01*
Y74622D01*
X1232211Y87633D01*
X1333557D01*
X1336034Y85156D01*
Y82542D01*
G01X339914Y82415D02*
X348450Y90951D01*
X354098D01*
X354692Y91545D01*
X354736D01*
X409685Y146494D01*
X495011D01*
X500416Y151899D01*
X578923D01*
X583347Y147475D01*
Y147474D01*
X584327Y146494D01*
X647689D01*
X695903Y194708D01*
X699161D01*
X702025Y197572D01*
Y201324D01*
X706074Y205373D01*
Y211989D01*
X724046Y229961D01*
Y292763D01*
X724141Y292858D01*
Y302931D01*
X759653Y338443D01*
X909850D01*
X925900Y354493D01*
X964276D01*
X972393Y346376D01*
Y45814D01*
X1023220Y-5013D01*
X1127364D01*
X1127365Y-5014D01*
X1128751D01*
X1163216Y29451D01*
X1210505D01*
X1225900Y44846D01*
Y71670D01*
X1230930Y76700D01*
X1333575D01*
X1334383Y75892D01*
G01X344304Y82439D02*
X351141Y89276D01*
X354896D01*
X405959Y140339D01*
X491762D01*
X501647Y150224D01*
X578229D01*
X581672Y146781D01*
Y146780D01*
X583633Y144819D01*
X668430D01*
X717331Y193720D01*
Y215346D01*
X737870Y235885D01*
Y299388D01*
X774450Y335968D01*
X789963D01*
X790093Y336098D01*
X911072D01*
X927792Y352818D01*
X963456D01*
X970493Y345781D01*
Y43057D01*
X1020238Y-6688D01*
X1126670D01*
X1126671Y-6689D01*
X1129445D01*
X1163910Y27776D01*
X1211199D01*
X1227575Y44152D01*
Y63975D01*
X1238625Y75025D01*
X1332474D01*
X1333570Y73929D01*
X1336079D01*
X1340961Y78811D01*
G01X345321Y102400D02*
X347715Y104794D01*
X348125D01*
X443330Y199999D01*
X454818D01*
X477516Y222697D01*
X648153D01*
X663416Y237960D01*
Y285852D01*
X729119Y351555D01*
X898622D01*
X913841Y366774D01*
X970312D01*
X985252Y351834D01*
Y55355D01*
X1035500Y5107D01*
X1124658D01*
X1159127Y39576D01*
X1206416D01*
X1215850Y49010D01*
Y81510D01*
X1225323Y90983D01*
X1329014D01*
X1332906Y94875D01*
X1341145D01*
X1347607Y101337D01*
G01X347647Y95614D02*
Y95465D01*
X349892Y93220D01*
X354042D01*
X408991Y148169D01*
X494317D01*
X499722Y153574D01*
X579617D01*
X585022Y148169D01*
X633565D01*
X675660Y190264D01*
X685337D01*
X690077Y195004D01*
Y200731D01*
X722371Y233025D01*
Y293457D01*
X722466Y293552D01*
Y303759D01*
X758825Y340118D01*
X908606D01*
X925045Y356557D01*
X965133D01*
X974627Y347063D01*
Y47333D01*
X1025298Y-3338D01*
X1128058D01*
X1162522Y31126D01*
X1209811D01*
X1224225Y45540D01*
Y72364D01*
X1230236Y78375D01*
X1315433D01*
X1319223Y82165D01*
X1330866D01*
X1334127Y78904D01*
X1338194D01*
X1340064Y80774D01*
X1341774D01*
X1341877Y80671D01*
X1346081D01*
G01X1426575Y96654D02*
X1423600Y99629D01*
Y119779D01*
X1409003Y134376D01*
X1389524D01*
X1363663Y108515D01*
X1347564D01*
X1340625Y101576D01*
X1334304D01*
X1334303Y101577D01*
X1330131D01*
X1324703Y96149D01*
X1315148D01*
X1313697Y97600D01*
X1307875D01*
X1302933Y92658D01*
X1224527D01*
X1214175Y82306D01*
Y49704D01*
X1205722Y41251D01*
X1158074D01*
X1124348Y7525D01*
X1037823D01*
X986927Y58421D01*
Y352529D01*
X970953Y368503D01*
X910480D01*
X895877Y353900D01*
X875678D01*
X875613Y353835D01*
X873987D01*
X873944Y353878D01*
X724530D01*
X660650Y289998D01*
Y240171D01*
X644851Y224372D01*
X476679D01*
X454718Y202411D01*
X443373D01*
X358666Y117704D01*
X355890D01*
X353001Y114815D01*
G01X351416Y95788D02*
X353834D01*
X416840Y158794D01*
X638165D01*
X706665Y227294D01*
Y300957D01*
X747939Y342231D01*
X908105D01*
X924160Y358286D01*
X967403D01*
X977133Y348556D01*
Y48959D01*
X1027685Y-1593D01*
X1126046D01*
X1126047Y-1594D01*
X1127433D01*
X1161828Y32801D01*
X1209117D01*
X1222550Y46234D01*
Y73058D01*
X1229542Y80050D01*
X1314175D01*
X1315155Y81030D01*
Y81031D01*
X1318266Y84142D01*
X1331258D01*
X1331560Y83840D01*
X1331561D01*
X1332541Y82860D01*
Y82859D01*
X1334821Y80579D01*
X1337500D01*
X1340247Y83326D01*
X1348641D01*
G01X553742Y267705D02*
X496192D01*
X456209Y227722D01*
X455550D01*
X356078Y128250D01*
X341596D01*
X337641Y124295D01*
Y114910D01*
G01X334947Y94605D02*
X336522Y93030D01*
X341932D01*
X346842Y97940D01*
X353381D01*
X415910Y160469D01*
X629690D01*
X688517Y219296D01*
Y226406D01*
X699774Y237663D01*
Y299498D01*
X744465Y344189D01*
X904809D01*
X920581Y359961D01*
X968098D01*
X979405Y348654D01*
Y50577D01*
X1029900Y82D01*
X1126740D01*
X1161134Y34476D01*
X1208423D01*
X1220875Y46928D01*
Y73928D01*
X1228672Y81725D01*
X1313480D01*
X1317572Y85817D01*
X1332597D01*
X1333281Y85133D01*
G01X335300Y926900D02*
X336900Y925300D01*
X432068D01*
X437368Y930600D01*
X551300D01*
X554700Y927200D01*
X668812D01*
X703912Y962300D01*
X760788D01*
X773199Y949889D01*
X875923D01*
X882712Y943100D01*
X911676D01*
X916204Y938572D01*
G01X337100Y972100D02*
X338500Y973500D01*
X870984D01*
X888184Y956300D01*
X930117D01*
X940268Y966451D01*
X969049D01*
X973900Y961600D01*
Y960000D01*
G01X905271Y974586D02*
Y972871D01*
X900500Y968100D01*
X894212D01*
X868592Y993720D01*
X864502D01*
X862723Y995499D01*
X677515D01*
X675916Y993900D01*
X559324D01*
X557587Y995637D01*
X344737D01*
G01X968900Y1026200D02*
Y1027304D01*
X960285Y1035919D01*
X946919D01*
X943600Y1032600D01*
X762988D01*
X761588Y1031200D01*
X350673D01*
G01X1041280Y1117700D02*
X1038800Y1120180D01*
Y1132353D01*
X1024846Y1146307D01*
X988184D01*
X981191Y1153300D01*
X964350D01*
X958879Y1158771D01*
X783517D01*
X772889Y1169399D01*
X761349D01*
X745628Y1185120D01*
X649281D01*
X644561Y1180400D01*
X634851D01*
X632725Y1178274D01*
X598578D01*
X593361Y1173057D01*
X513686D01*
X508770Y1177973D01*
X439984D01*
X435387Y1173376D01*
X408782D01*
X406358Y1175800D01*
X331679D01*
G01X1119042Y1238209D02*
X1115433Y1234600D01*
X1092774D01*
X1071474Y1255900D01*
X962900D01*
X948900Y1241900D01*
X750800D01*
X728500Y1219600D01*
X621000D01*
X618100Y1216700D01*
X315500D01*
G01X472244Y110827D02*
X469228Y113843D01*
Y124172D01*
X462575Y130825D01*
X423249D01*
X377144Y84720D01*
G01X472244Y116339D02*
X472339D01*
X474507Y118507D01*
Y122393D01*
X464400Y132500D01*
X414515D01*
X377944Y95929D01*
G01X911807Y1002342D02*
X912900Y1003435D01*
Y1007266D01*
X911227Y1008939D01*
X783947D01*
X783946Y1008938D01*
X779262D01*
X777500Y1010700D01*
X411334D01*
X408672Y1008038D01*
G01X1041280Y1091700D02*
X1038200Y1094780D01*
Y1096572D01*
X1036072Y1098700D01*
X1010895D01*
X975068Y1134527D01*
X817003D01*
X798180Y1115704D01*
X696708D01*
X682787Y1129625D01*
X468768D01*
X457316Y1118173D01*
X388888D01*
G01X398527Y1233336D02*
X653962D01*
X691183Y1270557D01*
X722790D01*
G01X456190Y354105D02*
X534905D01*
G01X452800Y420912D02*
X680288D01*
X741289Y359911D01*
X886289D01*
X887100Y359100D01*
G01X418600Y445462D02*
X830122D01*
X833185Y448525D01*
X864517D01*
X866317Y446725D01*
G01X421700Y450200D02*
X865221D01*
X866321Y451300D01*
G01X954921Y419291D02*
X934069D01*
X930719Y422641D01*
X929118D01*
X923800Y427959D01*
Y431799D01*
X923801Y431800D01*
Y434803D01*
X923800Y434804D01*
Y436069D01*
X909357Y450512D01*
Y456643D01*
X875385Y490615D01*
X723639D01*
X708924Y475900D01*
X447533D01*
G01X937205Y415354D02*
X928531D01*
X918750Y425135D01*
Y433977D01*
X904307Y448420D01*
Y454193D01*
X873085Y485415D01*
X729413D01*
X712337Y468339D01*
X461040D01*
X458679Y470700D01*
G01X866278Y459562D02*
X840542D01*
X837865Y456885D01*
X453177D01*
X450500Y459562D01*
G01X435082Y915200D02*
X435094Y915212D01*
X634988D01*
X707360Y842840D01*
X838687D01*
X866883Y871036D01*
X886464D01*
X901000Y856500D01*
X1014639D01*
X1027929Y843210D01*
X1050702D01*
X1054419Y839493D01*
G01X437600Y917800D02*
X437637Y917837D01*
X635934D01*
X708406Y845365D01*
X837641D01*
X865837Y873561D01*
X887510D01*
X901879Y859192D01*
X1034703D01*
X1037653Y862142D01*
Y876629D01*
X1038215Y877191D01*
G01X445582Y925352D02*
X670076D01*
X704824Y960100D01*
X759876D01*
X772287Y947689D01*
X875011D01*
X881800Y940900D01*
X904100D01*
X910258Y934742D01*
X917550D01*
G01X973900Y956200D02*
X971600Y958500D01*
Y960492D01*
X967841Y964251D01*
X941180D01*
X931029Y954100D01*
X887272D01*
X870472Y970900D01*
X452280D01*
X449137Y967757D01*
G01X1115105Y1002765D02*
X1110522Y1007348D01*
X1057228D01*
X1036995Y1027581D01*
X982181D01*
X975037Y1020437D01*
X964594D01*
X964593Y1020436D01*
X962967D01*
X962966Y1020437D01*
X918163D01*
X914863Y1023737D01*
X893868D01*
X892168Y1022037D01*
X766814D01*
X764313Y1024538D01*
X684389D01*
X684388Y1024537D01*
X436192D01*
X431562Y1019907D01*
Y1019869D01*
X429613Y1017920D01*
G01X1109593Y1002765D02*
X1107058Y1005300D01*
X1056907D01*
X1036301Y1025906D01*
X986606D01*
X979462Y1018762D01*
X965288D01*
X965287Y1018761D01*
X962273D01*
X962272Y1018762D01*
X917438D01*
X914138Y1022062D01*
X894562D01*
X892138Y1019638D01*
X780521D01*
X780021Y1020138D01*
X766331D01*
X763606Y1022863D01*
X685084D01*
X685083Y1022862D01*
X436886D01*
X433237Y1019213D01*
Y1015682D01*
X432657Y1015102D01*
G01X899846Y971468D02*
X894408D01*
X868177Y997699D01*
X676603D01*
X675004Y996100D01*
X561700D01*
X557100Y1000700D01*
X445000D01*
X442600Y998300D01*
G01X914948Y1063255D02*
X913799Y1064404D01*
X746766D01*
X735568Y1053206D01*
X720330D01*
X681763Y1091773D01*
X659893D01*
X621326Y1053206D01*
X601799D01*
X600805Y1054200D01*
X490120D01*
X488330Y1052410D01*
X414790D01*
X413000Y1054200D01*
G01X1036160Y1111900D02*
X1032460Y1115600D01*
X1012667D01*
X979367Y1148900D01*
X962413D01*
X956942Y1154371D01*
X781493D01*
X770865Y1164999D01*
X759525D01*
X748524Y1176000D01*
X636675D01*
X634549Y1173874D01*
X600402D01*
X595185Y1168657D01*
X511862D01*
X506948Y1173571D01*
X482928D01*
X478757Y1169400D01*
X441400D01*
G01X1047000Y1258687D02*
X1046987Y1258700D01*
X962374D01*
X948412Y1244738D01*
X750338D01*
X727400Y1221800D01*
X416900D01*
G01X1077300Y1271700D02*
X751182D01*
X738082Y1284800D01*
X688038D01*
X644064Y1328774D01*
X566004D01*
X563530Y1326300D01*
X412400D01*
X412300Y1326200D01*
G01X415422Y1352000D02*
X505321D01*
X510947Y1357626D01*
X544514D01*
X548988Y1362100D01*
X658679D01*
X668879Y1351900D01*
X820276D01*
X861076Y1392700D01*
X891000D01*
X896200Y1397900D01*
G01X929331Y419291D02*
X928897D01*
X921275Y426913D01*
Y435023D01*
X906832Y449466D01*
Y455268D01*
X874085Y488015D01*
X726712D01*
X711997Y473300D01*
X462133D01*
G01X954921Y442913D02*
X946246D01*
X945117Y444042D01*
X939329D01*
X934850Y439563D01*
X927448D01*
X914407Y452604D01*
Y459693D01*
X878435Y495665D01*
X496323D01*
X481533Y480875D01*
G01X919656Y998764D02*
Y1003987D01*
X912504Y1011139D01*
X792428D01*
X792427Y1011140D01*
X790566D01*
X790565Y1011139D01*
X780761D01*
X777599Y1014301D01*
X469099D01*
X465200Y1018200D01*
G01X908477Y1061823D02*
X747297D01*
X736480Y1051006D01*
X719418D01*
X680851Y1089573D01*
X660805D01*
X622238Y1051006D01*
X600887D01*
X599993Y1051900D01*
X506500D01*
G01X968900Y1022400D02*
X966700Y1024600D01*
Y1026392D01*
X964692Y1028400D01*
X944674D01*
X942689Y1030385D01*
X763885D01*
X762500Y1029000D01*
X531500D01*
X530800Y1028300D01*
G01X1053099Y1021657D02*
X1029062Y1045694D01*
X908828D01*
X905664Y1042530D01*
X759215D01*
X758425Y1041740D01*
X557099D01*
X556022Y1042817D01*
G01X1048512Y1021378D02*
X1026721Y1043169D01*
X910078D01*
X906914Y1040005D01*
X760261D01*
X759471Y1039215D01*
X554885D01*
X552500Y1041600D01*
Y1042430D01*
X552436Y1042494D01*
G01X1041280Y1100500D02*
X1038680Y1103100D01*
X1012719D01*
X976892Y1138927D01*
X815179D01*
X796356Y1120104D01*
X698532D01*
X684611Y1134025D01*
X609042D01*
X606367Y1136700D01*
X509037D01*
G01X522867Y1231097D02*
X654835D01*
X691165Y1267427D01*
X720446D01*
G01X1115105Y1273642D02*
X1111647Y1277100D01*
X1089700D01*
X1081800Y1269200D01*
X750570D01*
X737170Y1282600D01*
X687126D01*
X643152Y1326574D01*
X566916D01*
X564442Y1324100D01*
X520600D01*
G01X518397Y1360000D02*
X531000D01*
X535500Y1364500D01*
X826652D01*
X859370Y1397218D01*
X888118D01*
X896200Y1405300D01*
G01X527000Y1340600D02*
X527138Y1340738D01*
X557546D01*
X560020Y1343212D01*
X650048D01*
X661735Y1331525D01*
X829909D01*
X846010Y1347626D01*
X885375D01*
X895350Y1357601D01*
X963433D01*
X968132Y1362300D01*
X1025294D01*
X1031394Y1368400D01*
X1031422D01*
X1032452Y1369430D01*
X1081947D01*
X1083065Y1368312D01*
X1110986D01*
X1113530Y1365768D01*
G01X521500Y1342800D02*
X521963Y1343263D01*
X556500D01*
X558974Y1345737D01*
X651094D01*
X662781Y1334050D01*
X826834D01*
X845211Y1352427D01*
X886605D01*
X894304Y1360126D01*
X924626D01*
X927405Y1362905D01*
X964626D01*
X969121Y1367400D01*
X1026823D01*
X1030348Y1370925D01*
X1030376D01*
X1031740Y1372289D01*
X1081811D01*
X1083863Y1370237D01*
X1114573D01*
X1119042Y1365768D01*
G01X593365Y877358D02*
X665242D01*
X704810Y837790D01*
X841791D01*
X870681Y808900D01*
X873347D01*
X873977Y808270D01*
X875803D01*
X876433Y808900D01*
X884600D01*
X887600Y811900D01*
G01X592614Y882300D02*
X663871D01*
X705856Y840315D01*
X847815D01*
X864000Y856500D01*
X880764D01*
X885882Y861618D01*
G01X898617Y975434D02*
X893554D01*
X868888Y1000100D01*
X787595D01*
X787594Y1000099D01*
X675891D01*
X675192Y999400D01*
X572100D01*
X571400Y1000100D01*
G01X1081078Y1095362D02*
X1077138D01*
X1062800Y1109700D01*
X1035248D01*
X1031548Y1113400D01*
X1011755D01*
X978455Y1146700D01*
X961501D01*
X956030Y1152171D01*
X780581D01*
X769953Y1162799D01*
X750201D01*
X739200Y1173800D01*
X637587D01*
X632567Y1168780D01*
X602860D01*
X600640Y1171000D01*
G01X1115105Y1231123D02*
X1111682Y1227700D01*
X789727D01*
X776483Y1214456D01*
X592400D01*
G01X612000Y502300D02*
X616060Y506360D01*
X875760D01*
X926486Y557086D01*
X937205D01*
G01X910387Y1055344D02*
X906331Y1059400D01*
X747986D01*
X737391Y1048805D01*
X718507D01*
X679939Y1087373D01*
X664772D01*
X645200Y1067801D01*
Y1067800D01*
G01X1083660Y1092700D02*
X1076800D01*
X1062000Y1107500D01*
X1034336D01*
X1030636Y1111200D01*
X1010843D01*
X977543Y1144500D01*
X960589D01*
X955118Y1149971D01*
X779669D01*
X769041Y1160599D01*
X749401D01*
X741300Y1168700D01*
X660300D01*
X658900Y1170100D01*
X639039D01*
X636803Y1167864D01*
G01X1048960Y1095500D02*
Y1095940D01*
X1039600Y1105300D01*
X1013631D01*
X977803Y1141128D01*
X814268D01*
X798293Y1125153D01*
X696595D01*
X685523Y1136225D01*
X632603D01*
G01X1051300Y1253300D02*
X964100D01*
X950500Y1239700D01*
X798615D01*
X776215Y1217300D01*
X627632D01*
G01X839500Y508500D02*
X665326D01*
X658646Y515180D01*
G01X961100Y931640D02*
X951959D01*
X938299Y945300D01*
X883624D01*
X876835Y952089D01*
X774111D01*
X761700Y964500D01*
X703000D01*
X668600Y930100D01*
X658574D01*
G01X968780Y960000D02*
X966204Y962576D01*
X941874D01*
X931198Y951900D01*
X886360D01*
X870629Y967631D01*
X703019D01*
X680184Y944796D01*
X677457D01*
G01X947759Y998726D02*
X946080Y1000405D01*
X932398D01*
X926095Y1006708D01*
X920839D01*
X914108Y1013439D01*
X781573D01*
X778511Y1016501D01*
X665599D01*
X663800Y1018300D01*
G01X963780Y1026200D02*
X943762D01*
X941862Y1028100D01*
X765100D01*
X763500Y1026500D01*
X682200D01*
G01X895837Y978389D02*
X893711D01*
X869800Y1002300D01*
X786683D01*
X786682Y1002299D01*
X674979D01*
X674300Y1001620D01*
G01X1109593Y1273642D02*
X1106151Y1270200D01*
X1087800D01*
X1084400Y1266800D01*
X749858D01*
X736458Y1280200D01*
X666100D01*
X664000Y1278100D01*
G01X673000Y1354100D02*
X819364D01*
X860282Y1395018D01*
X889518D01*
X896100Y1401600D01*
G01X705348Y478425D02*
X720063Y493140D01*
X877360D01*
X911882Y458618D01*
Y451558D01*
X926197Y437243D01*
X926325D01*
Y436308D01*
X932919Y429714D01*
X933855D01*
X935817Y427752D01*
X937224D01*
X937283Y427693D01*
X943465D01*
X946874Y431102D01*
X947047D01*
G01X789739Y365493D02*
X790246Y366000D01*
X891631D01*
X899159Y373528D01*
X996243D01*
X1012583Y357188D01*
X1020250D01*
G01X776400Y956500D02*
X875536D01*
X884536Y947500D01*
X939257D01*
X950572Y936185D01*
X960503D01*
G01X968780Y956200D02*
X967702Y955122D01*
X936789D01*
X931367Y949700D01*
X885448D01*
X875848Y959300D01*
X780800D01*
G01X939544Y1003485D02*
X933955D01*
X928532Y1008908D01*
X921751D01*
X914659Y1016000D01*
X786800D01*
G01X963780Y1022400D02*
X963176Y1023004D01*
X917996D01*
X915300Y1025700D01*
X893054D01*
X891354Y1024000D01*
X784000D01*
G01X759500Y1056100D02*
X760300Y1056900D01*
X899152D01*
X904875Y1051177D01*
G01X792263Y1178661D02*
X812915D01*
X829554Y1195300D01*
X1007227D01*
X1011527Y1191000D01*
X1022212D01*
X1045212Y1168000D01*
X1046900D01*
G01X792263Y1174461D02*
X811084D01*
X828550Y1191927D01*
X992673D01*
X995800Y1188800D01*
X1021300D01*
X1045000Y1165100D01*
X1084200D01*
X1089743Y1170643D01*
X1115742D01*
X1119042Y1167343D01*
G01X792263Y1170261D02*
X792264Y1170260D01*
X809252D01*
X828482Y1189490D01*
X991998D01*
X994888Y1186600D01*
X1020388D01*
X1044681Y1162307D01*
X1086707D01*
X1088100Y1163700D01*
X1109887D01*
X1113530Y1167343D01*
G01X784544Y1210178D02*
X791466Y1217100D01*
X1037500D01*
X1048100Y1206500D01*
X1111381D01*
X1115105Y1202776D01*
G01X784544Y1205978D02*
X793466Y1214900D01*
X1036588D01*
X1060344Y1191144D01*
X1076032D01*
G01X779535Y1193469D02*
X798766Y1212700D01*
X1034100D01*
X1060000Y1186800D01*
X1074800D01*
X1086164Y1198164D01*
X1116568D01*
X1119042Y1195690D01*
G01X779535Y1189269D02*
X800766Y1210500D01*
X1032800D01*
X1059200Y1184100D01*
X1070000D01*
G01X779535Y1184669D02*
X803166Y1208300D01*
X1031888D01*
X1058288Y1181900D01*
X1074600D01*
X1083746Y1191046D01*
X1112662D01*
X1115105Y1188603D01*
G01X779535Y1180469D02*
X805166Y1206100D01*
X1030976D01*
X1057986Y1179090D01*
X1075600D01*
G01X797177Y1189537D02*
X815098D01*
X829461Y1203900D01*
X1029312D01*
X1056712Y1176500D01*
X1081000D01*
X1089600Y1185100D01*
X1115458D01*
X1119042Y1181516D01*
G01X1053743Y1174221D02*
X1026264Y1201700D01*
X829820D01*
X813457Y1185337D01*
X797225D01*
G01X792263Y1182861D02*
X814746D01*
X829385Y1197500D01*
X1008139D01*
X1012439Y1193200D01*
X1023124D01*
X1044724Y1171600D01*
X1080900D01*
X1087200Y1177900D01*
X1106123D01*
X1109593Y1174430D01*
G01X896500Y1341800D02*
X893800Y1339100D01*
X849543D01*
X830055Y1319612D01*
X792336D01*
Y1319537D01*
G01X1115105Y1358682D02*
X1111553Y1362234D01*
X1029191D01*
X1026494Y1359537D01*
X969277D01*
X964578Y1354838D01*
X896495D01*
X886520Y1344863D01*
X847155D01*
X830092Y1327800D01*
X790900D01*
X790290Y1328410D01*
G01X1109593Y1358682D02*
X1105931Y1355020D01*
X1071480D01*
X1067266Y1359234D01*
X1030434D01*
X1027737Y1356537D01*
X970902D01*
X966203Y1351838D01*
X897738D01*
X887763Y1341863D01*
X848398D01*
X831465Y1324930D01*
X788753D01*
X785640Y1328043D01*
Y1328370D01*
G01X1272755Y1137293D02*
X1272641Y1137179D01*
X1138183D01*
X1123070Y1152292D01*
X1045192D01*
X1032456Y1165028D01*
X994649D01*
X984295Y1175382D01*
X967763D01*
X966755Y1176390D01*
X823384D01*
X811238Y1164244D01*
X802036D01*
G01X803438Y1139700D02*
X809342Y1145604D01*
X954395D01*
G01X840945Y1622048D02*
X845287Y1617706D01*
Y1614917D01*
X845393Y1614811D01*
Y1591007D01*
X845287Y1590901D01*
Y1431937D01*
X869944Y1407280D01*
X874560D01*
X877643Y1404197D01*
X882226D01*
G01X840945Y1616536D02*
X843468Y1614013D01*
Y1591805D01*
X842762Y1591099D01*
Y1430891D01*
X869078Y1404575D01*
X873694D01*
G01X890982Y349498D02*
X901845D01*
X917446Y365099D01*
X969322D01*
X983577Y350844D01*
Y52686D01*
X1032831Y3432D01*
X1125352D01*
X1159746Y37826D01*
X1207035D01*
X1217525Y48316D01*
Y80816D01*
X1226017Y89308D01*
X1329709D01*
X1330689Y90288D01*
Y90289D01*
X1333600Y93200D01*
X1343827D01*
X1352351Y101724D01*
G01X887100Y359100D02*
X899853Y371853D01*
X972804D01*
X982108Y362549D01*
X985688D01*
G01X866276Y454900D02*
X877600D01*
X906900Y425600D01*
Y407474D01*
X931516Y382858D01*
X1041500D01*
G01X878193Y467707D02*
X909600Y436300D01*
Y409493D01*
X932056Y387037D01*
X1042943D01*
X1045292Y384688D01*
G01X891200Y838200D02*
X932447Y796953D01*
X1243647D01*
X1261189Y779411D01*
X1326089D01*
X1334300Y771200D01*
G01X888962Y843262D02*
X933596Y798628D01*
X1244942D01*
X1262484Y781086D01*
X1329074D01*
X1334329Y775831D01*
G01X874569Y811300D02*
Y811249D01*
X874500Y811318D01*
Y839500D01*
X880800Y845800D01*
X1006554D01*
X1019954Y832400D01*
X1085800D01*
X1086600Y833200D01*
G01X1089300Y836100D02*
X1088391Y837009D01*
X1018916D01*
X1007585Y848340D01*
X904660D01*
X888100Y864900D01*
X876894D01*
X873647Y861653D01*
G01X886792Y1404100D02*
X896889Y1414197D01*
Y1497107D01*
X886850Y1507146D01*
Y1567350D01*
X894730Y1575230D01*
Y1596287D01*
X895025Y1596582D01*
Y1614335D01*
X897638Y1616948D01*
Y1618111D01*
G01X873700Y1375746D02*
X874417Y1376463D01*
X915463D01*
X919475Y1380475D01*
X923643D01*
X927601Y1384433D01*
G01X923486Y1384268D02*
X918468D01*
X913601Y1379401D01*
X874570D01*
X873570Y1380401D01*
G01X897638Y1640945D02*
X896775D01*
X894520Y1638690D01*
Y1617400D01*
X893100Y1615980D01*
Y1597380D01*
X892805Y1597085D01*
Y1577305D01*
X885175Y1569675D01*
Y1506452D01*
X888800Y1502827D01*
Y1493500D01*
G01X904725Y1602363D02*
X907854Y1599234D01*
Y1586886D01*
X902500Y1581532D01*
Y1564402D01*
X893246Y1555148D01*
Y1548896D01*
X890200Y1545850D01*
Y1508534D01*
X900239Y1498495D01*
Y1424330D01*
X945318Y1379251D01*
X1020311D01*
X1061176Y1420116D01*
X1132549D01*
X1146401Y1406264D01*
Y1368726D01*
X1168227Y1346900D01*
X1740000D01*
G01X1842000Y1344700D02*
X1167315D01*
X1144088Y1367927D01*
Y1405182D01*
X1131354Y1417916D01*
X1062088D01*
X1021223Y1377051D01*
X945149D01*
X898564Y1423636D01*
Y1497801D01*
X888525Y1507840D01*
Y1546545D01*
X889505Y1547525D01*
X889506D01*
X891571Y1549590D01*
Y1555842D01*
X900300Y1564571D01*
Y1583216D01*
X904725Y1587641D01*
Y1598032D01*
G01X877828Y1500379D02*
X873794D01*
X856231Y1517942D01*
Y1528544D01*
X852672Y1532103D01*
Y1607949D01*
X848032Y1612589D01*
Y1612599D01*
G01X877946Y1496527D02*
X880476Y1499057D01*
Y1501226D01*
X878729Y1502973D01*
X875051D01*
X858756Y1519268D01*
Y1581144D01*
X864739Y1587127D01*
Y1624238D01*
X862205Y1626772D01*
G01X876096Y1505499D02*
X861281Y1520314D01*
Y1579498D01*
X866664Y1584881D01*
Y1626638D01*
X862205Y1631097D01*
Y1632284D01*
G01X922687Y93D02*
X922770Y176D01*
X997339D01*
X1016578Y-19063D01*
X1127716D01*
X1167029Y20250D01*
X1214318D01*
X1235101Y41033D01*
Y60856D01*
X1241744Y67499D01*
X1316602D01*
X1318264Y65837D01*
X1352346D01*
X1353963Y67454D01*
Y67456D01*
X1356463Y69956D01*
Y78280D01*
X1349271Y85472D01*
X1343521D01*
G01X1004082Y-38200D02*
Y-17970D01*
X994659Y-8547D01*
X928232D01*
X928138Y-8453D01*
G01X894965Y843500D02*
X896465Y842000D01*
X899000D01*
X938734Y802266D01*
X1247197D01*
X1265027Y784436D01*
X1331464D01*
X1338729Y777171D01*
Y776131D01*
G01X1338700Y771500D02*
X1336292Y773908D01*
Y776708D01*
X1330239Y782761D01*
X1264279D01*
X1246737Y800303D01*
X935697D01*
X897000Y839000D01*
G01X1643344Y887455D02*
X1640089Y884200D01*
X1452600D01*
X1444400Y876000D01*
X1289060D01*
X1250777Y837717D01*
X1096644D01*
X1048214Y886147D01*
X913862D01*
X904834Y895175D01*
Y907289D01*
X902400Y909723D01*
X900615D01*
G01X902571Y906534D02*
Y894029D01*
X912653Y883947D01*
X1047302D01*
X1095732Y835517D01*
X1251689D01*
X1288972Y872800D01*
X1445600D01*
X1455300Y882500D01*
X1644258D01*
X1646013Y884255D01*
G01X1639644Y889755D02*
X1636189Y886300D01*
X1451000D01*
X1442900Y878200D01*
X1288148D01*
X1249865Y839917D01*
X1097556D01*
X1049126Y888347D01*
X914903D01*
X907034Y896216D01*
Y908295D01*
X902359Y912970D01*
X898468D01*
G01X920810Y902210D02*
X930230Y911630D01*
X968266D01*
X974296Y905600D01*
X1010100D01*
X1011100Y904600D01*
G01X1025000Y897700D02*
X1025209Y897909D01*
Y901012D01*
X1023624Y902597D01*
X973176D01*
X966668Y909105D01*
X931276D01*
X928100Y905929D01*
Y900650D01*
G01X901540Y937712D02*
X903979D01*
X917565Y924126D01*
Y901435D01*
X924053Y894947D01*
X1051862D01*
X1100292Y846517D01*
X1247129D01*
X1286147Y885535D01*
X1312767D01*
G01X1435300Y882700D02*
X1286424D01*
X1248041Y844317D01*
X1099380D01*
X1050950Y892747D01*
X917235D01*
X911434Y898548D01*
Y910745D01*
X896679Y925500D01*
Y927505D01*
G01X1570500Y888400D02*
X1449900D01*
X1441900Y880400D01*
X1287236D01*
X1248953Y842117D01*
X1098468D01*
X1050038Y890547D01*
X915985D01*
X909234Y897298D01*
Y909207D01*
X901729Y916712D01*
X896420D01*
G01X931085Y936172D02*
X949279Y917978D01*
X1015309D01*
X1016842Y916445D01*
G01X1692100Y923600D02*
X1275460D01*
X1236205Y884345D01*
X1153835D01*
X1117427Y920753D01*
X1076226D01*
X1068680Y928299D01*
X1062672D01*
X1037770Y953201D01*
X994461D01*
X966368Y981294D01*
X963758D01*
X962516Y982536D01*
X934245D01*
X930704Y986077D01*
X906838D01*
X902991Y982230D01*
G01X1819541Y921500D02*
X1276772D01*
X1237417Y882145D01*
X1152879D01*
X1117122Y917902D01*
X1075965D01*
X1067768Y926099D01*
X1061760D01*
X1036858Y951001D01*
X993549D01*
X966050Y978500D01*
X945500D01*
X944900Y977900D01*
X927381D01*
X922407Y982874D01*
X909826D01*
G01X1521200Y928000D02*
X1273636D01*
X1236653Y891017D01*
X1154023D01*
X1119887Y925153D01*
X1078050D01*
X1070504Y932699D01*
X1064496D01*
X1039594Y957601D01*
X996285D01*
X968192Y985694D01*
X965582D01*
X960776Y990500D01*
X900184D01*
X895616Y985932D01*
G01X1636400Y925800D02*
X1274548D01*
X1235401Y886653D01*
X1154639D01*
X1118339Y922953D01*
X1077138D01*
X1069592Y930499D01*
X1063584D01*
X1038682Y955401D01*
X995373D01*
X967280Y983494D01*
X964670D01*
X963428Y984736D01*
X935157D01*
X931616Y988277D01*
X902621D01*
X896629Y982285D01*
G01X903442Y1003265D02*
X911463Y995244D01*
X920309D01*
X923180Y998115D01*
X943708D01*
X946579Y995244D01*
X962256D01*
X967400Y990100D01*
X976888D01*
X980371Y986617D01*
Y980039D01*
X990770Y969640D01*
X1020960D01*
X1025680Y964920D01*
X1055026D01*
X1090393Y929553D01*
X1121711D01*
X1155847Y895417D01*
X1227965D01*
X1259808Y927260D01*
G01X896371Y1002112D02*
X905445Y993038D01*
X961350D01*
X966494Y987894D01*
X969404D01*
X989858Y967440D01*
X1017960D01*
X1025600Y959800D01*
X1051815D01*
X1084262Y927353D01*
X1120799D01*
X1154935Y893217D01*
X1235741D01*
X1272724Y930200D01*
X1380300D01*
G01X1113530Y1337422D02*
X1110202Y1340750D01*
X1084987D01*
X1081037Y1344700D01*
X1012994D01*
X1011594Y1343300D01*
X898000D01*
X896500Y1341800D01*
G01X911516Y1573202D02*
Y1562456D01*
X899946Y1550886D01*
Y1546977D01*
X904036Y1542887D01*
X904037D01*
X904067Y1542857D01*
Y1507116D01*
X919349Y1491834D01*
Y1417668D01*
X948966Y1388051D01*
X1016663D01*
X1057528Y1428916D01*
X1137163D01*
X1155201Y1410878D01*
Y1372377D01*
X1170878Y1356700D01*
X1240276D01*
G01X1365551Y1353500D02*
X1170966D01*
X1153001Y1371465D01*
Y1409966D01*
X1136251Y1426716D01*
X1058440D01*
X1017575Y1385851D01*
X948054D01*
X917149Y1416756D01*
Y1490922D01*
X901867Y1506204D01*
Y1525591D01*
X901963Y1525687D01*
Y1527313D01*
X901867Y1527409D01*
Y1542687D01*
X898271Y1546283D01*
Y1552323D01*
X909100Y1563152D01*
Y1574286D01*
X911616Y1576802D01*
G01X1491662Y1351300D02*
X1170051D01*
X1150801Y1370550D01*
Y1408654D01*
X1134939Y1424516D01*
X1059352D01*
X1018487Y1383651D01*
X947142D01*
X914949Y1415844D01*
Y1490010D01*
X897547Y1507412D01*
Y1544638D01*
X896596Y1545589D01*
Y1553760D01*
X906900Y1564064D01*
Y1577565D01*
X911710Y1582375D01*
G01X1624500Y1349100D02*
X1169139D01*
X1148601Y1369638D01*
Y1407459D01*
X1133744Y1422316D01*
X1060264D01*
X1019399Y1381451D01*
X946230D01*
X912749Y1414932D01*
Y1489841D01*
X895872Y1506718D01*
Y1543943D01*
X894921Y1544894D01*
Y1554454D01*
X904700Y1564233D01*
Y1579529D01*
X911094Y1585923D01*
G01X904725Y1626378D02*
X901700Y1623353D01*
Y1589256D01*
X897038Y1584594D01*
Y1577600D01*
G01X1070918Y-73618D02*
X1067600Y-70300D01*
X1025300D01*
X1022500Y-67500D01*
X997800D01*
X994450Y-70850D01*
X989050D01*
G01X1500539Y739639D02*
X1495859Y734959D01*
X1352249D01*
X1346508Y740700D01*
X1342803D01*
X1340584Y738481D01*
X1262506D01*
X1231760Y769227D01*
X997602D01*
X968750Y740375D01*
X954425D01*
X952200Y742600D01*
G01X957100Y742900D02*
X967704D01*
X996556Y771752D01*
X1232806D01*
X1263552Y741006D01*
X1339538D01*
X1342332Y743800D01*
X1347932D01*
X1354203Y737529D01*
X1492529D01*
X1498000Y743000D01*
G01X953200Y736700D02*
X955400Y734500D01*
X972118D01*
X1001082Y763464D01*
X1228772D01*
X1259518Y732718D01*
X1346240D01*
X1347600Y734078D01*
G01X956900Y737600D02*
X970975D01*
X999839Y766464D01*
X1230615D01*
X1261361Y735718D01*
X1341980D01*
X1344062Y737800D01*
G01X949048Y755225D02*
Y753220D01*
X951268Y751000D01*
X963165D01*
X991492Y779327D01*
X1235944D01*
X1265325Y749946D01*
X1337765D01*
X1344119Y756300D01*
X1399842D01*
X1403714Y760172D01*
X1471519D01*
X1471992Y759699D01*
X1475947D01*
X1476558Y759088D01*
G01X1479033Y762259D02*
X1473003D01*
X1472565Y762697D01*
X1402668D01*
X1399346Y759375D01*
X1306312D01*
X1303305Y762382D01*
X1256460D01*
X1236990Y781852D01*
X989208D01*
X961008Y753652D01*
X952476D01*
G01X1354500Y747304D02*
X1342265D01*
X1338492Y743531D01*
X1264598D01*
X1233852Y774277D01*
X995510D01*
X966908Y745675D01*
X953525D01*
X951300Y747900D01*
G01X1360920Y749829D02*
X1341219D01*
X1337446Y746056D01*
X1265644D01*
X1234898Y776802D01*
X993067D01*
X964465Y748200D01*
X956200D01*
G01X1474083Y764750D02*
X1473611Y765222D01*
X1401622D01*
X1401150Y764750D01*
X1308079D01*
X1303469Y769360D01*
X1256624D01*
X1239082Y786902D01*
X985349D01*
X961988Y763541D01*
X947866D01*
G01X957629Y766231D02*
X957625Y766235D01*
X960504D01*
X983696Y789427D01*
X1240373D01*
X1257915Y771885D01*
X1304515D01*
X1307325Y769075D01*
X1471033D01*
X1471608Y768500D01*
G01X1373519Y761900D02*
X1307358D01*
X1304351Y764907D01*
X1257506D01*
X1238036Y784377D01*
X987318D01*
X963691Y760750D01*
X944500D01*
G01X967583Y933607D02*
X966220Y932244D01*
Y924856D01*
X971075Y920001D01*
X1016441D01*
X1030217Y906225D01*
X1031146D01*
X1039699Y897672D01*
X1052249D01*
X1101204Y848717D01*
X1245817D01*
X1284929Y887829D01*
X1391222D01*
X1392355Y886696D01*
G01X968698Y928957D02*
Y924747D01*
X971769Y921676D01*
X1017135D01*
X1030911Y907900D01*
X1031840D01*
X1040393Y899347D01*
X1053686D01*
X1102116Y850917D01*
X1244905D01*
X1287388Y893400D01*
X1440400D01*
X1440500Y893500D01*
G01X1584800Y895800D02*
X1584751Y895751D01*
X1286627D01*
X1243993Y853117D01*
X1109398D01*
X1058536Y903979D01*
X1038873D01*
X1032752Y910100D01*
X1031080D01*
X1017829Y923351D01*
X973755D01*
X971340Y925766D01*
Y931934D01*
X974484Y935078D01*
G01X1704010Y898000D02*
X1285764D01*
X1243081Y855317D01*
X1110310D01*
X1059448Y906179D01*
X1039785D01*
X1033664Y912300D01*
X1031249D01*
X1018523Y925026D01*
X975447D01*
X974259Y926214D01*
Y929468D01*
X976419Y931628D01*
G01X1824170Y886349D02*
X1810119Y900400D01*
X1285052D01*
X1242169Y857517D01*
X1111222D01*
X1060360Y908379D01*
X1040913D01*
X1031543Y917749D01*
X1028912D01*
X1019906Y926755D01*
X977596D01*
X976460Y927891D01*
G01X1823937Y890883D02*
X1811820Y903000D01*
X1284540D01*
X1241257Y859717D01*
X1112134D01*
X1061272Y910579D01*
X1044347D01*
X1023059Y931867D01*
X986490D01*
X981679Y936678D01*
G01X976213Y938846D02*
X984084D01*
X989388Y933542D01*
X1024160D01*
X1035028Y922674D01*
X1036979D01*
X1046874Y912779D01*
X1062184D01*
X1113046Y861917D01*
X1235937D01*
X1281020Y907000D01*
X1346076D01*
X1346080Y907004D01*
G01X966000Y937500D02*
X969873Y941373D01*
X983926D01*
X990082Y935217D01*
X1025263D01*
X1036131Y924349D01*
X1038416D01*
X1047765Y915000D01*
X1063075D01*
X1096872Y881203D01*
X1136622D01*
X1153708Y864117D01*
X1235025D01*
X1280908Y910000D01*
X1448000D01*
G01X1341219Y933282D02*
X1340600Y933901D01*
X1263074D01*
X1226790Y897617D01*
X1156759D01*
X1122623Y931753D01*
X1091305D01*
X1055938Y967120D01*
X1026607D01*
X1021887Y971840D01*
X991682D01*
X982571Y980951D01*
Y987529D01*
X977800Y992300D01*
X968312D01*
X961220Y999392D01*
Y1001600D01*
G01Y1005400D02*
X964140Y1002480D01*
Y999584D01*
X969224Y994500D01*
X980595D01*
X997758Y977337D01*
X1019502D01*
X1027519Y969320D01*
X1056850D01*
X1092217Y933953D01*
X1123535D01*
X1157671Y899817D01*
X1225878D01*
X1262195Y936134D01*
X1344499D01*
X1348233Y932400D01*
X1391000D01*
G01X966340Y1001600D02*
X967200Y1000740D01*
Y999636D01*
X970136Y996700D01*
X981507D01*
X998670Y979537D01*
X1020414D01*
X1028431Y971520D01*
X1057762D01*
X1093129Y936153D01*
X1124547D01*
X1158683Y902017D01*
X1224966D01*
X1261283Y938334D01*
X1345411D01*
X1349145Y934600D01*
X1393800D01*
X1398000Y930400D01*
X1505900D01*
G01X1633600Y936300D02*
X1633100Y936800D01*
X1350057D01*
X1346323Y940534D01*
X1260371D01*
X1224054Y904217D01*
X1159595D01*
X1125459Y938353D01*
X1094041D01*
X1058657Y973737D01*
X1029626D01*
X1021626Y981737D01*
X999582D01*
X982419Y998900D01*
X971048D01*
X969260Y1000688D01*
Y1002480D01*
X966340Y1005400D01*
G01X971460Y1001600D02*
X982831D01*
X1000494Y983937D01*
X1022538D01*
X1030538Y975937D01*
X1059569D01*
X1094953Y940553D01*
X1126371D01*
X1160507Y906417D01*
X1223142D01*
X1259459Y942734D01*
X1663266D01*
X1675000Y931000D01*
X1750200D01*
X1752000Y929200D01*
G01X971460Y1005400D02*
X973060Y1003800D01*
X983743D01*
X1001406Y986137D01*
X1023450D01*
X1031450Y978137D01*
X1060481D01*
X1081810Y956808D01*
X1113228D01*
X1161419Y908617D01*
X1222230D01*
X1258547Y944934D01*
X1664178D01*
X1675612Y933500D01*
X1807757D01*
X1813851Y927406D01*
G01X956600Y1001700D02*
X959000Y1004100D01*
Y1006292D01*
X960308Y1007600D01*
X988196D01*
X991000Y1004796D01*
Y1003100D01*
X1005763Y988337D01*
X1024362D01*
X1032062Y980637D01*
X1061093D01*
X1082722Y959008D01*
X1114140D01*
X1162331Y910817D01*
X1220317D01*
X1243200Y933700D01*
G01X956600Y1005700D02*
Y1007004D01*
X959396Y1009800D01*
X993000D01*
X1000700Y1002100D01*
Y998318D01*
X1008481Y990537D01*
X1025274D01*
X1032974Y982837D01*
X1062005D01*
X1083634Y961208D01*
X1115052D01*
X1163243Y913017D01*
X1212117D01*
X1264018Y964918D01*
X1287518D01*
X1294700Y972100D01*
X1378100D01*
G01X964537Y1160310D02*
X980553D01*
X990156Y1150707D01*
X1026922D01*
X1047412Y1130217D01*
X1092645D01*
X1120357Y1102505D01*
X1203995D01*
X1252400Y1054100D01*
G01X958870Y1163617D02*
X965793D01*
X966900Y1162510D01*
X981465D01*
X991068Y1152907D01*
X1027834D01*
X1048324Y1132417D01*
X1093557D01*
X1121269Y1104705D01*
X1206267D01*
X1282708Y1028264D01*
X1365537D01*
X1365551Y1028250D01*
G01X962941Y1165929D02*
X981158D01*
X991980Y1155107D01*
X1028746D01*
X1049236Y1134617D01*
X1094469D01*
X1122181Y1106905D01*
X1207651D01*
X1283975Y1030581D01*
X1481448D01*
X1481529Y1030500D01*
G01X967497Y1168802D02*
X981397D01*
X992892Y1157307D01*
X1029658D01*
X1050148Y1136817D01*
X1094638D01*
X1122350Y1109105D01*
X1208564D01*
X1284790Y1032879D01*
X1620006D01*
X1620059Y1032932D01*
G01X1691771Y1035163D02*
X1285618D01*
X1209476Y1111305D01*
X1122519D01*
X1094807Y1139017D01*
X1051145D01*
X1030655Y1159507D01*
X994281D01*
X982569Y1171219D01*
X957871D01*
G01X963000Y1174427D02*
X965941D01*
X966949Y1173419D01*
X983481D01*
X995193Y1161707D01*
X1031567D01*
X1049259Y1144015D01*
Y1143800D01*
X1051169Y1141890D01*
X1051384D01*
X1052057Y1141217D01*
X1094976D01*
X1122688Y1113505D01*
X1210388D01*
X1286530Y1037363D01*
X1861046D01*
X1864617Y1040934D01*
G01X1587400Y912200D02*
X1279996D01*
X1241141Y873345D01*
X1147833D01*
X1137775Y883403D01*
X1098016D01*
X1064120Y917299D01*
X1051998D01*
X1045461Y923836D01*
X1042347D01*
X1036431Y929752D01*
G01X1618200Y916800D02*
X1278296D01*
X1239241Y877745D01*
X1149899D01*
X1114439Y913205D01*
X1074438D01*
X1065944Y921699D01*
X1053822D01*
X1042221Y933300D01*
X1037083D01*
G01X1005294Y997940D02*
Y996706D01*
X1009263Y992737D01*
X1026186D01*
X1033886Y985037D01*
X1062917D01*
X1084546Y963408D01*
X1115964D01*
X1164155Y915217D01*
X1211205D01*
X1263106Y967118D01*
X1286654D01*
X1294036Y974500D01*
X1497073D01*
X1503394Y968179D01*
G01X1621787Y917108D02*
X1619895Y919000D01*
X1277384D01*
X1238329Y879945D01*
X1150811D01*
X1115351Y915405D01*
X1075350D01*
X1066856Y923899D01*
X1060848D01*
X1035947Y948800D01*
G01X1286000Y982200D02*
X1267500D01*
X1266100Y983600D01*
X1250300D01*
X1193830Y927130D01*
X1169847D01*
X1120573Y976404D01*
X1088974D01*
X1068453Y996925D01*
X1052359D01*
X1040181Y1009103D01*
X1028657D01*
G01X1263618Y990606D02*
Y990607D01*
X1231792D01*
X1203000Y1019399D01*
X1169871D01*
X1133576Y983104D01*
X1092851D01*
X1072330Y1003625D01*
X1056213D01*
X1035898Y1023940D01*
X1020654D01*
G01X1268378Y990608D02*
X1266413Y988643D01*
X1231050D01*
X1201969Y1017724D01*
X1171187D01*
X1134892Y981429D01*
X1091056D01*
X1070535Y1001950D01*
X1055182D01*
X1035892Y1021240D01*
X1018094D01*
G01X1271296Y986867D02*
X1271195Y986968D01*
X1230019D01*
X1200938Y1016049D01*
X1171881D01*
X1135586Y979754D01*
X1090362D01*
X1069841Y1000275D01*
X1054151D01*
X1035226Y1019200D01*
X1017358D01*
X1015534Y1021024D01*
Y1023840D01*
G01X1274413Y984613D02*
X1267859D01*
X1267179Y985293D01*
X1228988D01*
X1199907Y1014374D01*
X1172575D01*
X1136280Y978079D01*
X1089668D01*
X1069147Y998600D01*
X1053120D01*
X1034195Y1017525D01*
X1016664D01*
X1012974Y1021215D01*
Y1021240D01*
G01X1009509Y1009850D02*
X1014450D01*
X1020471Y1003829D01*
X1040716D01*
X1050970Y993575D01*
X1067065D01*
X1087711Y972929D01*
X1119079D01*
X1168228Y923780D01*
X1199118D01*
X1251745Y976407D01*
X1279599D01*
G01X1005294Y1001740D02*
X1007600Y999434D01*
Y997642D01*
X1010305Y994937D01*
X1027098D01*
X1034798Y987237D01*
X1063829D01*
X1085458Y965608D01*
X1116876D01*
X1165067Y917417D01*
X1210293D01*
X1262194Y969318D01*
X1285742D01*
X1293124Y976700D01*
X1574576D01*
G01X1615494Y973179D02*
X1609773Y978900D01*
X1292212D01*
X1284830Y971518D01*
X1261282D01*
X1209381Y919617D01*
X1165979D01*
X1117788Y967808D01*
X1086370D01*
X1064741Y989437D01*
X1035710D01*
X1028010Y997137D01*
X1011217D01*
X1010414Y997940D01*
G01X1629094Y975179D02*
X1623173Y981100D01*
X1291300D01*
X1283918Y973718D01*
X1251833D01*
X1199932Y921817D01*
X1166891D01*
X1118700Y970008D01*
X1087282D01*
X1065653Y991637D01*
X1036622D01*
X1028921Y999338D01*
X1012816D01*
X1010414Y1001740D01*
G01X1264269Y981248D02*
X1261283Y978262D01*
X1251231D01*
X1198424Y925455D01*
X1169153D01*
X1120004Y974604D01*
X1088405D01*
X1067759Y995250D01*
X1051664D01*
X1041410Y1005504D01*
X1024850D01*
X1023214Y1007140D01*
G01X1405315Y100591D02*
X1402400Y103506D01*
Y119887D01*
X1399354Y122933D01*
X1397291D01*
X1395965Y121607D01*
Y121258D01*
X1370300Y95593D01*
Y66587D01*
X1357550Y53837D01*
X1314812D01*
X1310400Y58249D01*
X1246351D01*
X1244352Y56250D01*
Y37202D01*
X1218124Y10974D01*
X1170835D01*
X1118555Y-41306D01*
X1083376D01*
X1078900Y-45782D01*
G01X1105315Y12599D02*
X1087311D01*
X1077505Y22405D01*
G01X1412402Y110827D02*
X1408186Y115043D01*
Y121470D01*
X1404798Y124858D01*
X1396493D01*
X1395594Y123959D01*
X1395095D01*
X1367775Y96639D01*
Y67633D01*
X1359254Y59112D01*
X1315477D01*
X1313815Y60774D01*
X1244530D01*
X1241826Y58070D01*
Y38247D01*
X1217104Y13525D01*
X1169815D01*
X1128190Y-28100D01*
X1043718D01*
X1043303Y-27685D01*
G01X1412402Y116339D02*
X1410139Y118602D01*
Y122240D01*
X1405596Y126783D01*
X1395695D01*
X1395396Y126484D01*
X1394049D01*
X1365250Y97685D01*
Y68679D01*
X1358208Y61637D01*
X1316523D01*
X1314861Y63299D01*
X1243484D01*
X1239301Y59116D01*
Y39293D01*
X1216058Y16050D01*
X1168769D01*
X1128059Y-24660D01*
X1045873D01*
G01X1043513Y-21696D02*
X1044108Y-21101D01*
X1128047D01*
X1167723Y18575D01*
X1215012D01*
X1236776Y40339D01*
Y60162D01*
X1242438Y65824D01*
X1315908D01*
X1317386Y64346D01*
Y64345D01*
X1317569Y64162D01*
X1357162D01*
X1359350Y66350D01*
G01X1105315Y28347D02*
X1104580Y29082D01*
X1082418D01*
X1080418Y31082D01*
X1076418D01*
G01X1097441Y32284D02*
X1081585D01*
X1081112Y32757D01*
X1079369D01*
X1076944Y35182D01*
G01X1105315Y36221D02*
X1104290Y37246D01*
X1088454D01*
X1083088Y42612D01*
X1077260D01*
G01X1115157Y44095D02*
X1110752Y48500D01*
X1104046D01*
X1100546Y52000D01*
X1077400D01*
G01X1123031Y32284D02*
X1103348D01*
X1100061Y35571D01*
X1087760D01*
X1084349Y38982D01*
X1077082D01*
G01X1115157Y36221D02*
X1111807Y39571D01*
X1102765D01*
X1098828Y43508D01*
X1085792D01*
X1083105Y46195D01*
X1076905D01*
G01X1115157Y28347D02*
X1114847D01*
X1111600Y25100D01*
X1102300D01*
X1100118Y27282D01*
X1076299D01*
G01X1608200Y914400D02*
X1279084D01*
X1240229Y875545D01*
X1148745D01*
X1138687Y885603D01*
X1098928D01*
X1065032Y919499D01*
X1052601D01*
X1044970Y927130D01*
X1044101D01*
G01X1048960Y1113900D02*
Y1114760D01*
X1051880Y1117680D01*
Y1118680D01*
X1053100Y1119900D01*
X1072600D01*
X1094374Y1098126D01*
X1101358D01*
X1116284Y1083200D01*
X1216173D01*
X1277707Y1021666D01*
X1678347D01*
X1685047Y1014966D01*
G01X1680087Y1023983D02*
X1679970Y1023866D01*
X1278619D01*
X1217085Y1085400D01*
X1120600D01*
X1105500Y1100500D01*
X1096000D01*
X1074400Y1122100D01*
X1052200D01*
X1048960Y1118860D01*
Y1117700D01*
G01Y1091700D02*
X1053051Y1087609D01*
X1094601D01*
X1111361Y1070849D01*
X1214609D01*
X1256142Y1029316D01*
G01X1048960Y1099300D02*
X1058451Y1089809D01*
X1095513D01*
X1112273Y1073049D01*
X1215998D01*
X1274207Y1014840D01*
X1349829D01*
G01X1054080Y1113900D02*
X1066607D01*
X1088498Y1092009D01*
X1096425D01*
X1113185Y1075249D01*
X1216910D01*
X1275019Y1017140D01*
X1478168D01*
X1478194Y1017166D01*
G01X1054080Y1117700D02*
X1065223D01*
X1086997Y1095926D01*
X1100446D01*
X1115372Y1081000D01*
X1214271D01*
X1275905Y1019366D01*
X1602400D01*
G01X1518701Y120276D02*
X1520964Y122539D01*
Y125958D01*
X1436497Y210425D01*
X1261402D01*
X1227702Y176725D01*
X1133700D01*
Y176500D01*
X1134110D01*
G01X1511614Y102166D02*
X1508200Y105580D01*
Y127600D01*
X1437835Y197965D01*
X1256049D01*
X1225684Y167600D01*
X1136203D01*
G01X1375700Y413400D02*
X1367775Y421325D01*
X1130859D01*
X1128825Y419291D01*
X1123031D01*
G01X1418225Y421700D02*
X1416075Y423850D01*
X1127711D01*
X1126502Y422641D01*
X1121643D01*
X1118293Y419291D01*
X1097441D01*
G01X1414882Y397271D02*
X1385708D01*
X1364179Y418800D01*
X1132881D01*
X1130022Y415941D01*
X1122341D01*
X1118404Y412004D01*
X1112204D01*
X1108854Y415354D01*
X1105315D01*
G01X1226045Y431102D02*
X1115157D01*
G01X1115105Y1031111D02*
X1118109Y1028107D01*
X1169057D01*
X1172736Y1031786D01*
G01X1109593Y1031111D02*
X1112975Y1034493D01*
X1174629D01*
X1177036Y1032086D01*
G01X1239900Y1024000D02*
Y1025800D01*
X1211611Y1054089D01*
X1108211D01*
X1091400Y1070900D01*
G01X1091494Y1075994D02*
Y1074006D01*
X1109211Y1056289D01*
X1213164D01*
X1266787Y1002666D01*
X1384800D01*
G01X1097800Y1070700D02*
X1110011Y1058489D01*
X1214076D01*
X1267891Y1004674D01*
X1451774D01*
X1451800Y1004700D01*
G01X1097500Y1075100D02*
X1100500Y1072100D01*
Y1070500D01*
X1110311Y1060689D01*
X1214988D01*
X1268611Y1007066D01*
X1580381D01*
G01X1671422Y1009266D02*
X1269523D01*
X1215900Y1062889D01*
X1111511D01*
X1103800Y1070600D01*
G01Y1075600D02*
X1114311Y1065089D01*
X1216812D01*
X1270375Y1011526D01*
X1690279D01*
G01X1119042Y1224036D02*
X1122610Y1227604D01*
X1205303D01*
G01X1115105Y1216949D02*
X1118656Y1220500D01*
X1273788D01*
X1275114Y1221826D01*
X1466974D01*
X1467000Y1221800D01*
G01X1119042Y1209863D02*
X1122579Y1213400D01*
X1272970D01*
X1274796Y1215226D01*
X1401172D01*
X1401311Y1215365D01*
X1702773D01*
X1702838Y1215300D01*
G01X1113530Y1209863D02*
X1114737D01*
X1118375Y1206225D01*
X1268907D01*
X1275708Y1213026D01*
X1402084D01*
X1402223Y1213165D01*
X1755439D01*
X1755900Y1212704D01*
G01X1710617Y1231429D02*
X1709100Y1229912D01*
X1274888D01*
X1255700Y1249100D01*
X1122324D01*
X1119042Y1252382D01*
G01X1113530D02*
X1117148Y1256000D01*
X1257812D01*
X1281212Y1232600D01*
X1705500D01*
X1706900Y1234000D01*
X1715049D01*
G01X1254800Y1269600D02*
X1254100Y1270300D01*
X1121500D01*
X1119042Y1267842D01*
Y1266556D01*
G01X1473600Y1242777D02*
X1468336Y1237513D01*
X1283675D01*
X1258188Y1263000D01*
X1118636D01*
X1115105Y1259469D01*
G01X1497200Y1342500D02*
X1164500D01*
X1141925Y1365075D01*
Y1387075D01*
X1137500Y1391500D01*
X1121657D01*
X1119042Y1394115D01*
G01X1501600Y1342300D02*
Y1341800D01*
X1500200Y1340400D01*
X1488409D01*
X1488146Y1340663D01*
X1163037D01*
X1140000Y1363700D01*
Y1385500D01*
X1136000Y1389500D01*
X1119000D01*
X1114385Y1394115D01*
X1113530D01*
G01X1504528Y100591D02*
X1499914Y105205D01*
Y121397D01*
X1468207Y153104D01*
X1430753D01*
X1423487Y160370D01*
X1396070D01*
X1389651Y153951D01*
X1380161D01*
X1349828Y123618D01*
X1197637D01*
X1178656Y104637D01*
G01X1447835Y100591D02*
X1443200Y105226D01*
Y121418D01*
X1420785Y143833D01*
X1388303D01*
X1363868Y119398D01*
X1340072D01*
X1337596Y116922D01*
X1196874D01*
X1176952Y97000D01*
Y93390D01*
G01X1215795Y181242D02*
X1193877D01*
X1191835Y179200D01*
X1140550D01*
G01X1518701Y106103D02*
X1516152Y108652D01*
Y126518D01*
X1437718Y204952D01*
X1285991D01*
X1282416Y201377D01*
X1254723D01*
X1227983Y174637D01*
X1142800D01*
G01X1518701Y100591D02*
X1514227Y105065D01*
Y125417D01*
X1440004Y199640D01*
X1255355D01*
X1227115Y171400D01*
X1140500D01*
G01X1176300Y284500D02*
X1181588Y279212D01*
X1189996D01*
X1193617Y282833D01*
X1341653D01*
X1351911Y272575D01*
X1371975D01*
X1372274Y272874D01*
G01X1374338Y292900D02*
X1373813Y293425D01*
X1189578D01*
X1180953Y284800D01*
G01X1172736Y1031786D02*
X1175347Y1029175D01*
X1196795D01*
X1232737Y993233D01*
X1280146D01*
X1281064Y992315D01*
X1484000D01*
G01X1177036Y1032086D02*
X1177089Y1032139D01*
X1197402D01*
X1233783Y995758D01*
X1481500D01*
G01X1388500Y1224900D02*
X1275076D01*
X1273238Y1223062D01*
X1152800D01*
G01X1152700Y1216213D02*
X1272671D01*
X1273884Y1217426D01*
X1400260D01*
X1400399Y1217565D01*
X1558511D01*
X1558650Y1217426D01*
G01X1355733Y1241900D02*
X1353546Y1239713D01*
X1284587D01*
X1258200Y1266100D01*
X1181400D01*
G01X1613400Y1236500D02*
X1612213Y1235313D01*
X1282187D01*
X1257400Y1260100D01*
X1184000D01*
G01X1381800Y1329600D02*
Y1329141D01*
X1377133Y1324474D01*
X1164174D01*
X1149700Y1310000D01*
X1144000D01*
G01X1369600Y1330100D02*
X1369500Y1330000D01*
X1157000D01*
X1154500Y1327500D01*
G01X1373700Y1330000D02*
X1370463Y1333237D01*
X1154648D01*
X1150911Y1329500D01*
G01X1518701Y114764D02*
X1522889Y118952D01*
Y126756D01*
X1435134Y214511D01*
X1262712D01*
X1229443Y181242D01*
X1215795D01*
G01X1439654Y349852D02*
X1437587Y347785D01*
Y325274D01*
X1437588Y325273D01*
Y323183D01*
X1370832Y256427D01*
Y256426D01*
X1369354Y254948D01*
X1235452D01*
X1223000Y267400D01*
X1200400D01*
X1194700Y261700D01*
G01X1189700Y308527D02*
Y305297D01*
X1197897Y297100D01*
X1262075D01*
G01X1190200Y285023D02*
X1346240D01*
X1355991Y275272D01*
G01X1201835Y305319D02*
X1208657Y312141D01*
X1407126D01*
X1426915Y331930D01*
Y354317D01*
X1431909Y359311D01*
G01X1358573Y290900D02*
X1191453D01*
X1185588Y285035D01*
G01X1444238Y349852D02*
X1441931Y352159D01*
X1438254D01*
X1435062Y348967D01*
Y324228D01*
X1368307Y257473D01*
X1238227D01*
X1225775Y269925D01*
X1206475D01*
X1197000Y279400D01*
G01X1440748Y110827D02*
X1436554Y115021D01*
Y121571D01*
X1420399Y137726D01*
X1388136D01*
X1364745Y114335D01*
X1341823D01*
X1339012Y111524D01*
X1314123D01*
X1304563Y101964D01*
Y100771D01*
G01X1440748Y116339D02*
X1438485Y118602D01*
Y122363D01*
X1421447Y139401D01*
X1387442D01*
X1364051Y116010D01*
X1341129D01*
X1338318Y113199D01*
X1311439D01*
X1299569Y101329D01*
Y100639D01*
G01X1419488Y114764D02*
X1416695Y117557D01*
Y123113D01*
X1407957Y131851D01*
X1391090D01*
X1363417Y104178D01*
X1346798D01*
X1341671Y99051D01*
X1333258D01*
X1333257Y99052D01*
X1331177D01*
X1325749Y93624D01*
X1314102D01*
X1312263Y95463D01*
G01X1433661Y114764D02*
X1428838Y119587D01*
Y121607D01*
X1414394Y136051D01*
X1388830D01*
X1365439Y112660D01*
X1346099D01*
X1338014Y104575D01*
X1330760D01*
X1324297Y98112D01*
X1315961D01*
G01X1419488Y100591D02*
X1418292D01*
X1415584Y103299D01*
Y114495D01*
X1414770Y115309D01*
Y122129D01*
X1413457Y123442D01*
X1412706D01*
X1407139Y129009D01*
X1392375D01*
X1361786Y98420D01*
Y84919D01*
X1358355Y81488D01*
G01X1504528Y106103D02*
X1502010Y108621D01*
Y122872D01*
X1469253Y155629D01*
X1431799D01*
X1424473Y162955D01*
X1394083D01*
X1388957Y157829D01*
X1369399D01*
X1349931Y138361D01*
G01X1427663Y167032D02*
X1423397D01*
X1420995Y164630D01*
X1409364D01*
X1405355Y168639D01*
X1397398D01*
X1389979Y161220D01*
X1363263D01*
X1343535Y141492D01*
Y133515D01*
X1338400Y128380D01*
Y126015D01*
G01X1447835Y106103D02*
X1445275Y108663D01*
Y132647D01*
X1428877Y149045D01*
X1411292D01*
X1408781Y146534D01*
X1387274D01*
X1364017Y123277D01*
G01X1525787Y110827D02*
X1529975Y115015D01*
Y125953D01*
X1534703Y130681D01*
X1545195D01*
X1550942Y136428D01*
Y181350D01*
X1546032Y186260D01*
Y208921D01*
X1516119Y238834D01*
Y516781D01*
X1513200Y519700D01*
G01X1525787Y116339D02*
X1528050Y118602D01*
Y128437D01*
X1532819Y133206D01*
X1544149D01*
X1548417Y137474D01*
Y180304D01*
X1543507Y185214D01*
Y207875D01*
X1513594Y237788D01*
Y512806D01*
X1510300Y516100D01*
X1509800D01*
G01X1755010Y966285D02*
X1752223Y969072D01*
X1733484D01*
X1726269Y961857D01*
X1674934D01*
X1674814Y961977D01*
G01X1677056Y954636D02*
X1783447D01*
X1797463Y968652D01*
G01X1680012Y952402D02*
X1796619D01*
X1806077Y961860D01*
G01X1812050Y1071223D02*
X1810900Y1070073D01*
Y1062200D01*
X1801147Y1052447D01*
X1686653D01*
X1685100Y1054000D01*
G01X1679300Y1043169D02*
X1682828Y1039641D01*
X1856377D01*
X1872162Y1055426D01*
G54D11*
X19712Y1176350D03*
X72500Y508600D03*
X67500D03*
X39325Y1131400D03*
X36848Y1173600D03*
X31500Y1224000D03*
X39425Y1226200D03*
X37225Y1230100D03*
X45518Y1336366D03*
X41381Y1335567D03*
X114300Y992362D03*
X137163Y987125D03*
X148400Y1086900D03*
X148300Y1228800D03*
X163500Y1345200D03*
X196712Y508600D03*
X191712D03*
X207313Y598113D03*
X212063Y585741D03*
X203863Y575125D03*
X181000Y580362D03*
X199900Y923200D03*
X195100Y1096800D03*
X223100Y920600D03*
X239000Y985600D03*
X252100Y990100D03*
X244600Y1004600D03*
X261100Y1005700D03*
X264864Y1120500D03*
X303000Y73500D03*
X291601Y418503D03*
X293763Y582925D03*
X268100Y982300D03*
X273300Y981700D03*
X280800Y1011900D03*
X281200Y1033000D03*
X271100Y1063200D03*
X281500Y1036744D03*
X315500Y1216700D03*
X276100Y1229100D03*
X286925Y1201945D03*
X295900Y1339700D03*
X296100Y1335100D03*
X279900Y1328300D03*
X283700D03*
X286100Y1349659D03*
X292600Y1337367D03*
X289510Y1342259D03*
X361776Y70842D03*
X335081Y104081D03*
X339219Y95188D03*
X339914Y82415D03*
X344304Y82439D03*
X345321Y102400D03*
X347647Y95614D03*
X353001Y114815D03*
X351416Y95788D03*
X337641Y114910D03*
X334947Y94605D03*
X320925Y508600D03*
X315925D03*
X335300Y926900D03*
X337100Y972100D03*
X344737Y995637D03*
X350673Y1031200D03*
X331679Y1175800D03*
X377144Y84720D03*
X377944Y95929D03*
X408672Y1008038D03*
X388888Y1118173D03*
X398527Y1233336D03*
X456190Y354105D03*
X452800Y420912D03*
X418600Y445462D03*
X421700Y450200D03*
X447533Y475900D03*
X458679Y470700D03*
X450500Y459562D03*
X435082Y915200D03*
X437600Y917800D03*
X445582Y925352D03*
X449137Y967757D03*
X429613Y1017920D03*
X432657Y1015102D03*
X442600Y998300D03*
X413000Y1054200D03*
X441400Y1169400D03*
X416900Y1221800D03*
X412300Y1326200D03*
X415422Y1352000D03*
X462133Y473300D03*
X481533Y480875D03*
X472022Y582062D03*
X465200Y1018200D03*
X506500Y1051900D03*
X509180Y145419D03*
X553742Y267705D03*
X534905Y354105D03*
X530800Y1028300D03*
X556022Y1042817D03*
X552436Y1042494D03*
X509037Y1136700D03*
X522867Y1231097D03*
X520600Y1324100D03*
X518397Y1360000D03*
X512900Y1345600D03*
X553587Y1346026D03*
X527000Y1340600D03*
X521500Y1342800D03*
X593365Y877358D03*
X592614Y882300D03*
X571400Y1000100D03*
X600640Y1171000D03*
X592400Y1214456D03*
X619171Y112329D03*
X612000Y502300D03*
X645200Y1067800D03*
X636803Y1167864D03*
X632603Y1136225D03*
X627632Y1217300D03*
X687566Y109568D03*
X658646Y515180D03*
X658574Y930100D03*
X677457Y944796D03*
X663800Y1018300D03*
X682200Y1026500D03*
X674300Y1001620D03*
X664000Y1278100D03*
X673000Y1354100D03*
X705348Y478425D03*
X728174Y1275611D03*
X725678Y1272799D03*
X722790Y1270557D03*
X720446Y1267427D03*
X731500Y1277811D03*
X789739Y365493D03*
X776400Y956500D03*
X780800Y959300D03*
X786800Y1016000D03*
X784000Y1024000D03*
X759500Y1056100D03*
X779535Y1180469D03*
X792263Y1178661D03*
Y1174461D03*
Y1170261D03*
X784544Y1210178D03*
Y1205978D03*
X779535Y1193469D03*
Y1189269D03*
Y1184669D03*
X797177Y1189537D03*
X797225Y1185337D03*
X792263Y1182861D03*
X792336Y1319537D03*
X790290Y1328410D03*
X785640Y1328370D03*
X839500Y508500D03*
X802036Y1164244D03*
X803438Y1139700D03*
X881750Y37397D03*
X858496Y37121D03*
X881549Y326304D03*
X890982Y349498D03*
X887100Y359100D03*
X887500Y378495D03*
X866276Y454900D03*
X866317Y446725D03*
X866321Y451300D03*
X878193Y467707D03*
X866278Y459562D03*
X887600Y811900D03*
X891200Y838200D03*
X874569Y811300D03*
X885882Y861618D03*
X894965Y843500D03*
X888962Y843262D03*
X873647Y861653D03*
X895616Y985932D03*
X873259Y1365805D03*
X886792Y1404100D03*
X882226Y1404197D03*
X873694Y1404575D03*
X873700Y1375746D03*
X873570Y1380401D03*
X888800Y1493500D03*
X877828Y1500379D03*
X877946Y1496527D03*
X876096Y1505499D03*
X873922Y1477766D03*
X876200Y1553900D03*
X876190Y1537187D03*
X876100Y1549000D03*
X876200Y1558400D03*
X848551Y1542440D03*
X922687Y93D03*
X928138Y-8453D03*
X897000Y839000D03*
X903000Y842500D03*
X920810Y902210D03*
X928100Y900650D03*
X900615Y909723D03*
X902571Y906534D03*
X903368Y934568D03*
X904594Y931141D03*
X916204Y938572D03*
X917550Y934742D03*
X901540Y937712D03*
X896679Y927505D03*
X896420Y916712D03*
X898468Y912970D03*
X931085Y936172D03*
X912994Y971921D03*
X910397Y979189D03*
X902991Y982230D03*
X909826Y982874D03*
X905271Y974586D03*
X899846Y971468D03*
X898617Y975434D03*
X895837Y978389D03*
X896629Y982285D03*
X904601Y998556D03*
X910040Y1006613D03*
X911807Y1002342D03*
X919656Y998764D03*
X939544Y1003485D03*
X903442Y1003265D03*
X896371Y1002112D03*
X920770Y1067389D03*
X921149Y1062424D03*
X914948Y1063255D03*
X908477Y1061823D03*
X910387Y1055344D03*
X904875Y1051177D03*
X896500Y1341800D03*
X896212Y1345788D03*
X895900Y1390100D03*
X896200Y1386000D03*
X896100Y1393800D03*
X896200Y1397900D03*
Y1405300D03*
X896100Y1401600D03*
X923829Y1389012D03*
X936994Y1379895D03*
X927601Y1384433D03*
X923486Y1384268D03*
X897038Y1577600D03*
X911516Y1573202D03*
X911616Y1576802D03*
X911710Y1582375D03*
X911094Y1585923D03*
X992185Y-54411D03*
X989050Y-70850D03*
X985688Y362549D03*
X977794Y695103D03*
X952200Y742600D03*
X957100Y742900D03*
X977622Y699464D03*
X953200Y736700D03*
X956900Y737600D03*
X949048Y755225D03*
X952476Y753652D03*
X951300Y747900D03*
X956200Y748200D03*
X957320Y769818D03*
X947866Y763541D03*
X957629Y766231D03*
X952820Y769518D03*
X944500Y760750D03*
X961100Y931640D03*
X960503Y936185D03*
X967583Y933607D03*
X968698Y928957D03*
X974484Y935078D03*
X976419Y931628D03*
X976460Y927891D03*
X981679Y936678D03*
X976213Y938846D03*
X966000Y937500D03*
X979020Y960000D03*
Y956200D03*
X973900Y960000D03*
Y956200D03*
X968780Y960000D03*
Y956200D03*
X947759Y998726D03*
X961220Y1001600D03*
Y1005400D03*
X966340Y1001600D03*
Y1005400D03*
X971460Y1001600D03*
Y1005400D03*
X974020Y1026200D03*
Y1022400D03*
X968900Y1026200D03*
Y1022400D03*
X963780Y1026200D03*
Y1022400D03*
X956600Y1001700D03*
Y1005700D03*
X964537Y1160310D03*
X958870Y1163617D03*
X962941Y1165929D03*
X967497Y1168802D03*
X957871Y1171219D03*
X963000Y1174427D03*
X954395Y1145604D03*
X1004082Y-38200D03*
X993000Y-60600D03*
X1020250Y357188D03*
X1038215Y877191D03*
X1011100Y904600D03*
X1025000Y897700D03*
X1036431Y929752D03*
X1037083Y933300D03*
X1016842Y916445D03*
X1035947Y948800D03*
X1028657Y1009103D03*
X1020654Y1023940D03*
X1018094Y1021240D03*
X1015534Y1023840D03*
X1012974Y1021240D03*
X1013700Y1007640D03*
X1009509Y1009850D03*
X1005294Y997940D03*
Y1001740D03*
X1010414Y997940D03*
Y1001740D03*
X1023214Y1007140D03*
X1036160Y1095500D03*
Y1091700D03*
Y1111900D03*
X1016835Y1323916D03*
X1016672Y1338228D03*
X1016600Y1332000D03*
X1043112Y-34912D03*
X1078900Y-45782D03*
X1070918Y-73618D03*
X1043303Y-27685D03*
X1045873Y-24660D03*
X1043513Y-21696D03*
X1077505Y22405D03*
X1076418Y31082D03*
X1076944Y35182D03*
X1077260Y42612D03*
X1077400Y52000D03*
X1077082Y38982D03*
X1076905Y46195D03*
X1076299Y27282D03*
X1041500Y382858D03*
X1045292Y384688D03*
X1054419Y839493D03*
Y828081D03*
X1086600Y833200D03*
X1044101Y927130D03*
X1053099Y1021657D03*
X1048512Y1021378D03*
X1048960Y1113900D03*
Y1117700D03*
X1041280Y1121500D03*
Y1113900D03*
Y1117700D03*
X1081078Y1095362D03*
X1083660Y1092700D03*
X1041280Y1095500D03*
Y1091700D03*
Y1100500D03*
X1048960Y1095500D03*
Y1091700D03*
Y1099300D03*
X1054080Y1113900D03*
Y1117700D03*
X1075600Y1179090D03*
X1053743Y1174221D03*
X1046900Y1168000D03*
X1052522Y1145153D03*
X1076032Y1191144D03*
X1070000Y1184100D03*
X1079500Y1276100D03*
X1047000Y1258687D03*
X1051300Y1253300D03*
X1077300Y1271700D03*
X1103300Y-60000D03*
X1115603Y-60293D03*
X1134110Y176500D03*
X1136203Y167600D03*
X1089300Y836100D03*
X1091400Y1070900D03*
X1091494Y1075994D03*
X1097800Y1070700D03*
X1097500Y1075100D03*
X1103800Y1070600D03*
Y1075600D03*
X1128800Y1125100D03*
X1178656Y104637D03*
X1176952Y93390D03*
X1140550Y179200D03*
X1142800Y174637D03*
X1140500Y171400D03*
X1176300Y284500D03*
X1180953Y284800D03*
X1185588Y285035D03*
X1169768Y730300D03*
Y723100D03*
Y726700D03*
X1175568Y712300D03*
X1171968D03*
X1175568Y715900D03*
X1171968D03*
X1173368Y730300D03*
X1171968Y719500D03*
X1175568D03*
X1173368Y726700D03*
Y723100D03*
X1172736Y1031786D03*
X1177036Y1032086D03*
X1170140Y1043939D03*
X1152800Y1223062D03*
X1152700Y1216213D03*
X1181400Y1266100D03*
X1184000Y1260100D03*
X1144000Y1310000D03*
X1150232Y1316358D03*
X1154500Y1327500D03*
X1150911Y1329500D03*
X1215795Y181242D03*
X1194700Y261700D03*
X1189700Y308527D03*
X1190200Y285023D03*
X1201835Y305319D03*
X1197000Y279400D03*
X1226045Y431102D03*
X1205303Y1227604D03*
X1250016Y247017D03*
X1262075Y297100D03*
X1264878Y508068D03*
X1263250Y823436D03*
X1243200Y933700D03*
X1259808Y927260D03*
X1271296Y986867D03*
X1274413Y984613D03*
X1279599Y976407D03*
X1264269Y981248D03*
X1263618Y990606D03*
X1268378Y990608D03*
X1239900Y1024000D03*
X1256142Y1029316D03*
X1252400Y1054100D03*
X1272755Y1137293D03*
X1254800Y1269600D03*
X1240276Y1356700D03*
X1304563Y100771D03*
X1299569Y100639D03*
X1312263Y95463D03*
X1315961Y98112D03*
X1324134Y126967D03*
X1316000Y772200D03*
X1310500Y774700D03*
X1312767Y885535D03*
X1286000Y982200D03*
X1284695Y956586D03*
X1309600Y1068173D03*
X1351200Y68600D03*
X1359350Y66350D03*
X1358355Y81488D03*
X1338215Y107586D03*
X1336034Y82542D03*
X1334383Y75892D03*
X1340961Y78811D03*
X1343521Y85472D03*
X1347607Y101337D03*
X1346081Y80671D03*
X1348641Y83326D03*
X1352351Y101724D03*
X1333281Y85133D03*
X1354500Y75400D03*
X1349931Y138361D03*
X1338400Y126015D03*
X1364017Y123277D03*
X1337662Y137188D03*
X1372274Y272874D03*
X1355991Y275272D03*
X1374338Y292900D03*
X1358573Y290900D03*
X1375700Y413400D03*
X1359882Y508014D03*
X1364882D03*
X1347600Y734078D03*
X1344062Y737800D03*
X1354500Y747304D03*
X1360920Y749829D03*
X1334300Y771200D03*
X1338729Y776131D03*
X1338700Y771500D03*
X1334329Y775831D03*
X1373519Y761900D03*
X1341219Y933282D03*
X1346080Y907004D03*
X1378100Y972100D03*
X1362382Y961355D03*
X1349829Y1014840D03*
X1365551Y1028250D03*
X1334500Y1121173D03*
X1355733Y1241900D03*
X1369600Y1330100D03*
X1373700Y1330000D03*
X1365551Y1353500D03*
X1427663Y167032D03*
X1384475Y255839D03*
X1414882Y397271D03*
X1418225Y421700D03*
X1392355Y886696D03*
X1391000Y932400D03*
X1380300Y930200D03*
X1384800Y1002666D03*
X1388500Y1224900D03*
X1381800Y1329600D03*
X1463804Y138605D03*
X1444238Y349852D03*
X1439654D03*
X1431909Y359311D03*
X1474083Y764750D03*
X1471608Y768500D03*
X1435300Y882700D03*
X1440500Y893500D03*
X1448000Y910000D03*
X1451800Y1004700D03*
X1467000Y1221800D03*
X1473600Y1242777D03*
X1499775Y248061D03*
X1486594Y508098D03*
X1491594D03*
X1513200Y519700D03*
X1509800Y516100D03*
X1500539Y739639D03*
X1498000Y743000D03*
X1489000Y723000D03*
X1476558Y759088D03*
X1479033Y762259D03*
X1486600Y786559D03*
X1505900Y930400D03*
X1521200Y928000D03*
X1503394Y968179D03*
X1484000Y992315D03*
X1481500Y995758D03*
X1478194Y1017166D03*
X1481529Y1030500D03*
X1491662Y1351300D03*
X1494662Y1336000D03*
X1497200Y1342500D03*
X1501600Y1342300D03*
X1526000Y728000D03*
X1570500Y888400D03*
X1558650Y1217426D03*
X1584800Y895800D03*
X1587400Y912200D03*
X1608200Y914400D03*
X1618200Y916800D03*
X1574576Y976700D03*
X1615494Y973179D03*
X1580381Y1007066D03*
X1602400Y1019366D03*
X1620059Y1032932D03*
X1613400Y1236500D03*
X1643344Y887455D03*
X1646013Y884255D03*
X1639644Y889755D03*
X1633600Y936300D03*
X1621787Y917108D03*
X1636400Y925800D03*
X1629094Y975179D03*
X1624500Y1349100D03*
X1692100Y923600D03*
X1704010Y898000D03*
X1674814Y961977D03*
X1677056Y954636D03*
X1680012Y952402D03*
X1685047Y1014966D03*
X1680087Y1023983D03*
X1671422Y1009266D03*
X1690279Y1011526D03*
X1691771Y1035163D03*
X1685100Y1054000D03*
X1679300Y1043169D03*
X1702838Y1215300D03*
X1710617Y1231429D03*
X1715049Y1234000D03*
X1752000Y929200D03*
X1755010Y966285D03*
X1756100Y1004362D03*
X1755900Y1212704D03*
X1740000Y1346900D03*
X1813851Y927406D03*
X1797463Y968652D03*
X1806077Y961860D03*
X1787163Y1009741D03*
X1778963Y999125D03*
X1812050Y1071223D03*
X1824170Y886349D03*
X1819541Y921500D03*
X1823937Y890883D03*
X1842000Y1344700D03*
X1867963Y996425D03*
X1872162Y1055426D03*
X1864617Y1040934D03*
X1873500Y1329000D03*
G54D12*
X465157Y114764D03*
X472244Y116339D03*
Y110827D03*
X536024Y114764D03*
X521850D03*
X543110Y116339D03*
Y110827D03*
X536024Y120276D03*
X840945Y1616536D03*
Y1622048D03*
X848032Y1612599D03*
X890552Y1616536D03*
X862205Y1626772D03*
Y1632284D03*
X890552Y1622048D03*
Y1640551D03*
Y1644882D03*
X904725Y1602363D03*
Y1598032D03*
Y1626378D03*
X897638Y1618111D03*
Y1640945D03*
X1109593Y1002765D03*
X1115105D03*
X1109593Y1031111D03*
X1115105D03*
X1109593Y1160257D03*
Y1174430D03*
X1113530Y1167343D03*
X1119042D03*
X1115105Y1188603D03*
Y1202776D03*
Y1216949D03*
X1113530Y1209863D03*
X1119042Y1181516D03*
Y1195690D03*
Y1209863D03*
Y1224036D03*
X1109593Y1245296D03*
Y1273642D03*
X1115105Y1231123D03*
Y1245296D03*
Y1259469D03*
Y1273642D03*
X1113530Y1252382D03*
X1119042Y1238209D03*
Y1252382D03*
Y1266556D03*
X1115105Y1287816D03*
X1119042Y1280729D03*
X1109593Y1358682D03*
X1115105D03*
X1113530Y1337422D03*
Y1351595D03*
Y1365768D03*
X1119042D03*
X1109593Y1401201D03*
X1113530Y1394115D03*
X1119042D03*
Y1408288D03*
X1412402Y116339D03*
X1419488Y114764D03*
X1426575Y96654D03*
X1405315Y100591D03*
X1419488D03*
X1412402Y110827D03*
X1433661Y114764D03*
X1440748Y116339D03*
X1447835Y100591D03*
Y106103D03*
X1440748Y110827D03*
X1518701Y114764D03*
X1490354D03*
X1518701Y106103D03*
X1504528D03*
X1518701Y100591D03*
X1504528D03*
X1511614Y102166D03*
X1518701Y120276D03*
X1525787Y116339D03*
Y110827D03*
G54D13*
X929331Y419291D03*
X937205Y415354D03*
Y557086D03*
X954921Y142520D03*
X947047Y138583D03*
X954921Y442913D03*
Y419291D03*
X947047Y431102D03*
X1105315Y12599D03*
X1123031Y32284D03*
X1097441D03*
X1115157Y44095D03*
Y36221D03*
Y28347D03*
X1105315Y36221D03*
Y28347D03*
X1123031Y419291D03*
X1097441D03*
X1115157Y431102D03*
X1105315Y415354D03*
X1097441Y718504D03*
X1105315Y714567D03*
G54D14*
X1039845Y1467746D03*
X1026345D03*
X1030845D03*
X1035345D03*
X1039845Y1463246D03*
X1026345D03*
X1030845D03*
X1035345D03*
X1005400Y1463157D03*
X1000900D03*
X996400D03*
X1009900D03*
X1005400Y1467657D03*
X1000900D03*
X996400D03*
X1009900D03*
X1035345Y1476746D03*
X1030845D03*
X1026345D03*
X1039845D03*
Y1472246D03*
X1026345D03*
X1030845D03*
X1035345D03*
X1005400Y1472157D03*
X1000900D03*
X996400D03*
X1009900D03*
Y1476657D03*
X1005400D03*
X1000900D03*
X996400D03*
X1023583Y1489593D03*
X995783D03*
X1000500Y1511400D03*
X1036578Y1511210D03*
X1014690Y1511178D03*
X1010190D03*
X1005690D03*
X1031790Y1511078D03*
X1027290D03*
X1019600Y1511100D03*
X1023583Y1501593D03*
Y1507593D03*
Y1495593D03*
X995783D03*
Y1501593D03*
Y1507593D03*
X1040583Y1517883D03*
X1031799Y1534392D03*
X1031882Y1528985D03*
X1026459Y1528919D03*
X1026376Y1534326D03*
X1014867D03*
X1014950Y1528919D03*
X1020290Y1534392D03*
X1020373Y1528985D03*
X1040500Y1529290D03*
X1040583Y1523883D03*
X1062700Y1463100D03*
X1058200D03*
X1067200D03*
X1062700Y1467600D03*
X1058200D03*
X1067200D03*
X1053700Y1463100D03*
Y1467600D03*
X1062700Y1472100D03*
X1058200D03*
X1067200D03*
Y1476600D03*
X1058200D03*
X1062700D03*
X1053700Y1472100D03*
Y1476600D03*
X1078683Y1489593D03*
X1051383D03*
X1041810Y1511084D03*
X1055310D03*
X1059810D03*
X1064310D03*
X1068810D03*
X1073310D03*
X1078683Y1495593D03*
Y1501593D03*
Y1507593D03*
Y1516593D03*
X1051383Y1495593D03*
Y1501593D03*
Y1507593D03*
X1078683Y1522593D03*
G54D15*
X1101457Y1601181D03*
X1119685D03*
X1108150D03*
X1126378D03*
G54D16*
G01X114300Y992362D02*
X127038D01*
X132275Y987125D01*
X137163D01*
G01X207313Y598113D02*
X209613D01*
X223287Y611787D01*
X316888D01*
X346613Y582062D01*
X472022D01*
G01X212063Y585741D02*
X290947D01*
X293763Y582925D01*
G01X203863Y575125D02*
X195975D01*
X190738Y580362D01*
X181000D01*
G01X1109593Y1160257D02*
X1106036Y1156700D01*
X1088200D01*
X1085593Y1159307D01*
X1043438D01*
X1020994Y1181751D01*
X994545D01*
X989569Y1186727D01*
X829627D01*
X810397Y1167497D01*
X783903D01*
X776801Y1174599D01*
X764501D01*
X737198Y1201902D01*
X286968D01*
X286925Y1201945D01*
G01X1119042Y1408288D02*
X1115570Y1411760D01*
X1063460D01*
X1025400Y1373700D01*
X931200D01*
X922900Y1365400D01*
X885300D01*
X879300Y1359400D01*
X845447D01*
X824860Y1338813D01*
X664755D01*
X653068Y1350500D01*
X554000D01*
X549526Y1346026D01*
X519526D01*
X515759Y1342259D01*
X289510D01*
G01X521850Y114764D02*
X518564Y118050D01*
Y128034D01*
X509180Y137418D01*
Y145419D01*
G01X543110Y110827D02*
X546318Y114035D01*
Y124164D01*
X549161Y127007D01*
X570293D01*
X603409Y93891D01*
X810175D01*
X823326Y80740D01*
Y65346D01*
X823325Y65345D01*
Y63689D01*
X841595Y45419D01*
Y45418D01*
X842685Y44328D01*
X842686D01*
X842830Y44184D01*
X859882D01*
X873251Y30815D01*
X904541D01*
X931148Y4208D01*
X997215D01*
X1017723Y-16300D01*
X1126571D01*
X1165884Y23013D01*
X1213173D01*
X1232338Y42178D01*
Y62001D01*
X1240599Y70262D01*
X1328171D01*
X1329833Y68600D01*
X1351200D01*
G01X543110Y116339D02*
X540610Y118839D01*
Y121851D01*
X548166Y129407D01*
X571193D01*
X604709Y95891D01*
X809346D01*
X809347Y95892D01*
X811003D01*
X825326Y81569D01*
Y64517D01*
X843659Y46184D01*
X861278D01*
X873933Y33529D01*
X905278D01*
X931506Y7301D01*
X997833D01*
X1019434Y-14300D01*
X1125742D01*
X1165055Y25013D01*
X1212344D01*
X1230338Y43007D01*
Y62830D01*
X1239770Y72262D01*
X1329000D01*
X1330662Y70600D01*
X1349700D01*
X1354500Y75400D01*
G01X512900Y1345600D02*
X515326Y1348026D01*
X548697D01*
X553171Y1352500D01*
X654700D01*
X664900Y1342300D01*
X824443D01*
X864943Y1382800D01*
X913092D01*
X919304Y1389012D01*
X923829D01*
G01X1109593Y1401201D02*
X1106792Y1398400D01*
X1053700D01*
X1026245Y1370945D01*
X968338D01*
X963061Y1365668D01*
X926260D01*
X923481Y1362889D01*
X885889D01*
X880400Y1357400D01*
X846276D01*
X825689Y1336813D01*
X663926D01*
X652239Y1348500D01*
X556061D01*
X553587Y1346026D01*
G01X890552Y1622048D02*
X889448D01*
X885142Y1617742D01*
Y1576742D01*
X873300Y1564900D01*
Y1556800D01*
X876200Y1553900D01*
G01X876190Y1537187D02*
Y1544561D01*
X867800Y1552951D01*
Y1566100D01*
X879654Y1577954D01*
Y1638554D01*
X885982Y1644882D01*
X890552D01*
G01Y1640551D02*
X887551D01*
X882113Y1635113D01*
Y1577313D01*
X870500Y1565700D01*
Y1554600D01*
X876100Y1549000D01*
G01X890552Y1616536D02*
X887654Y1613638D01*
Y1576062D01*
X876200Y1564608D01*
Y1558400D01*
G01X903000Y842500D02*
X940045Y805455D01*
X1247916D01*
X1266171Y787200D01*
X1485959D01*
X1486600Y786559D01*
G01X1113530Y1351595D02*
X1109435Y1347500D01*
X939400D01*
X938231Y1348669D01*
X899093D01*
X896212Y1345788D01*
G01X977794Y695103D02*
X1041155Y758464D01*
X1224136D01*
X1259600Y723000D01*
X1489000D01*
G01X977622Y699464D02*
X1038622Y760464D01*
X1227229D01*
X1261645Y726048D01*
X1524048D01*
X1526000Y728000D01*
G01X1316000Y772200D02*
X1315862Y772338D01*
X1309750D01*
X1307440Y774648D01*
X1259215D01*
X1241673Y792190D01*
X979692D01*
X957320Y769818D01*
G01X1310500Y774700D02*
X1308552Y776648D01*
X1260044D01*
X1242502Y794190D01*
X977492D01*
X952820Y769518D01*
G01X993000Y-60600D02*
X994430Y-59170D01*
X1014982D01*
X1015812Y-60000D01*
X1053300D01*
X1060400Y-52900D01*
X1096200D01*
X1103300Y-60000D01*
G01X992185Y-54411D02*
X1005889D01*
X1007000Y-53300D01*
X1032600D01*
X1037700Y-48200D01*
X1097125D01*
X1109218Y-60293D01*
X1115603D01*
G01X1113530Y1351595D02*
X1116735Y1354800D01*
X1139500D01*
X1156400Y1337900D01*
X1487000D01*
X1488900Y1336000D01*
X1494662D01*
G01X1150232Y1316358D02*
X1161111Y1327237D01*
X1375837D01*
X1381700Y1333100D01*
X1869400D01*
X1873500Y1329000D01*
G01X1490354Y114764D02*
X1487600Y117518D01*
Y119874D01*
X1471873Y135601D01*
X1466808D01*
X1463804Y138605D01*
G01X1778963Y999125D02*
X1774363D01*
X1769126Y1004362D01*
X1756100D01*
G01X1867963Y996425D02*
Y1004437D01*
X1864800Y1007600D01*
X1789304D01*
X1787163Y1009741D01*
G54D17*
G01X67500Y508600D02*
X72500D01*
G01D02*
X191712D01*
G01D02*
X196712D01*
G01D02*
X315925D01*
G01X363248Y-425196D02*
Y-505196D01*
G01D02*
X1639148D01*
G01X359248Y-409196D02*
G02I-12000J0D01*
G01X354098D02*
G02I-6850J0D01*
G01X347248Y-425196D02*
Y-393196D01*
G01X363248Y-425196D02*
X1639148D01*
G01X363248Y-460696D02*
X1639148D01*
G01X363248Y-409196D02*
X331248D01*
G01X315925Y508600D02*
X320925D01*
G01X619171Y112329D02*
X684805D01*
X687566Y109568D01*
G01X881750Y37397D02*
Y43398D01*
X876464Y48684D01*
X844695D01*
X827826Y65553D01*
Y82605D01*
X806542Y103889D01*
X695264D01*
X689585Y109568D01*
X687566D01*
G01X720748Y-425196D02*
Y-505196D01*
G01X858248Y-425196D02*
Y-505196D01*
G01X858496Y37121D02*
X869099Y26518D01*
X891222D01*
X919526Y-1786D01*
X919527D01*
X922836Y-5095D01*
X996854D01*
X1017162Y-25403D01*
X1033603D01*
X1043112Y-34912D01*
G01X936994Y1379895D02*
X933699Y1376600D01*
X930300D01*
X921600Y1367900D01*
X884264D01*
X882169Y1365805D01*
X873259D01*
G01X873922Y1477766D02*
Y1495636D01*
X848551Y1521007D01*
Y1542440D01*
G01X973248Y-425196D02*
Y-505196D01*
G01X1263250Y823436D02*
X1059064D01*
X1054419Y828081D01*
G01X1052522Y1145153D02*
X1119330D01*
X1131485Y1132998D01*
X1276530D01*
X1288355Y1121173D01*
X1334500D01*
G01X1128800Y1125100D02*
X1132517Y1128817D01*
X1254079D01*
X1274807Y1108089D01*
X1295960D01*
X1299504Y1104545D01*
Y1080696D01*
X1306950Y1073250D01*
Y1070823D01*
X1309600Y1068173D01*
G01X1862652Y846508D02*
X1850994Y858166D01*
Y926480D01*
X1846502Y930972D01*
X1835138D01*
X1829110Y937000D01*
X1677062D01*
X1615041Y999021D01*
X1237101D01*
X1192183Y1043939D01*
X1170140D01*
G01X1271648Y-425196D02*
Y-505196D01*
G01X1384475Y255839D02*
X1375939D01*
X1367117Y247017D01*
X1250016D01*
G01X1359882Y508014D02*
X1359936Y508068D01*
X1264878D01*
G01X1324134Y126967D02*
X1327441D01*
X1337662Y137188D01*
G01X1284695Y956586D02*
X1289295Y961186D01*
X1362213D01*
X1362382Y961355D01*
G01X1486594Y508098D02*
X1481296Y502800D01*
X1370096D01*
X1364882Y508014D01*
G01D02*
X1359882D01*
G01X1384475Y255839D02*
X1491997D01*
X1499775Y248061D01*
G01X1441648Y-425196D02*
Y-505196D01*
G01X1491594Y508098D02*
X1486594D01*
G01X1639148Y-425196D02*
Y-505196D01*
G01X1667148Y-409196D02*
G02I-12000J0D01*
G01X1661998D02*
G02I-6850J0D01*
G01X1655148Y-425196D02*
Y-393196D01*
G01X1671148Y-409196D02*
X1639148D01*
G54D18*
G01X394744Y-485863D02*
X395618Y-484988D01*
X396273Y-483530D01*
X396710Y-481487D01*
X396273Y-479738D01*
X395400Y-478571D01*
X393871Y-477696D01*
X387976D01*
Y-495196D01*
X395181D01*
X396710Y-494030D01*
X397583Y-492279D01*
X398020Y-490238D01*
X397583Y-488196D01*
X396273Y-486446D01*
X394744Y-485863D01*
X387976D01*
G01X407441Y-495196D02*
Y-483530D01*
G01Y-485863D02*
X408533Y-484696D01*
X409625Y-483821D01*
X411153Y-483530D01*
X412244Y-483821D01*
X413555Y-484696D01*
G01X423413Y-500446D02*
X424723Y-501029D01*
X426470Y-500446D01*
X427561Y-499280D01*
X428435Y-497821D01*
X429744Y-493155D01*
X432583Y-483530D01*
G01X425596D02*
X429744Y-493155D01*
G01X448991Y-484988D02*
X447463Y-483821D01*
X446153Y-483530D01*
X444406Y-484113D01*
X443096Y-485279D01*
X442223Y-487321D01*
X442004Y-489363D01*
X442223Y-491405D01*
X443096Y-493155D01*
X444406Y-494613D01*
X446153Y-495196D01*
X447681Y-494613D01*
X448991Y-493446D01*
G01X459723Y-487321D02*
X466710D01*
X466055Y-485279D01*
X464963Y-484113D01*
X463435Y-483530D01*
X461906Y-483821D01*
X460596Y-484696D01*
X459723Y-486738D01*
X459286Y-488488D01*
Y-490238D01*
X459723Y-491988D01*
X460815Y-493738D01*
X462125Y-494904D01*
X463653Y-495196D01*
X465181Y-494613D01*
X466710Y-492863D01*
G01X502801Y-479155D02*
X501491Y-478279D01*
X499963Y-477696D01*
X498216D01*
X496251Y-478571D01*
X494723Y-480029D01*
X493631Y-481780D01*
X492758Y-484696D01*
X492539Y-487321D01*
X492976Y-489946D01*
X493631Y-491696D01*
X494941Y-493446D01*
X496470Y-494613D01*
X497998Y-495196D01*
X499526D01*
X501055Y-494613D01*
X502365Y-493738D01*
X503457Y-492572D01*
G01X519428Y-495196D02*
Y-483530D01*
G01Y-485571D02*
X518555Y-484405D01*
X517244Y-483821D01*
X515716Y-483530D01*
X514188Y-484113D01*
X512878Y-485279D01*
X512004Y-487029D01*
X511568Y-489363D01*
X512004Y-491696D01*
X512878Y-493446D01*
X514188Y-494613D01*
X515716Y-495196D01*
X517244Y-494904D01*
X518555Y-494030D01*
X519428Y-492863D01*
G01X529286Y-495196D02*
Y-483530D01*
G01Y-486446D02*
X530160Y-484988D01*
X531470Y-483821D01*
X533216Y-483530D01*
X534744Y-483821D01*
X536055Y-484988D01*
X536710Y-487029D01*
Y-495196D01*
G01X545913Y-500446D02*
X547223Y-501029D01*
X548970Y-500446D01*
X550061Y-499280D01*
X550935Y-497821D01*
X552244Y-493155D01*
X555083Y-483530D01*
G01X548096D02*
X552244Y-493155D01*
G01X567998Y-495196D02*
X566688Y-494904D01*
X565378Y-493738D01*
X564504Y-491696D01*
X564068Y-489363D01*
X564504Y-487029D01*
X565378Y-484988D01*
X566688Y-483821D01*
X567998Y-483530D01*
X569308Y-483821D01*
X570618Y-484988D01*
X571491Y-487029D01*
X571710Y-489363D01*
X571491Y-491696D01*
X570618Y-493738D01*
X569308Y-494904D01*
X567998Y-495196D01*
G01X581786D02*
Y-483530D01*
G01Y-486446D02*
X582660Y-484988D01*
X583970Y-483821D01*
X585716Y-483530D01*
X587244Y-483821D01*
X588555Y-484988D01*
X589210Y-487029D01*
Y-495196D01*
G01X616350D02*
Y-477696D01*
X624646D01*
G01X621590Y-486154D02*
X616350D01*
G01X637998Y-495779D02*
X637561Y-495488D01*
Y-494904D01*
X637998Y-494613D01*
X638435Y-494904D01*
Y-495488D01*
X637998Y-495779D01*
G01X650695Y-495196D02*
Y-477696D01*
X655061D01*
X656808Y-478571D01*
X658118Y-479738D01*
X659210Y-481487D01*
X660083Y-483530D01*
X660301Y-486446D01*
X660083Y-489363D01*
X659210Y-491405D01*
X658118Y-493155D01*
X656808Y-494321D01*
X655061Y-495196D01*
X650695D01*
G01X668631D02*
Y-477696D01*
X673871D01*
X675618Y-478571D01*
X676928Y-480613D01*
X677365Y-482946D01*
X676928Y-485279D01*
X675836Y-487029D01*
X673871Y-487905D01*
X668631D01*
G01X692244Y-485863D02*
X693118Y-484988D01*
X693773Y-483530D01*
X694210Y-481487D01*
X693773Y-479738D01*
X692900Y-478571D01*
X691371Y-477696D01*
X685476D01*
Y-495196D01*
X692681D01*
X694210Y-494030D01*
X695083Y-492279D01*
X695520Y-490238D01*
X695083Y-488196D01*
X693773Y-486446D01*
X692244Y-485863D01*
X685476D01*
G01X501071Y-450196D02*
Y-432696D01*
X506748Y-447279D01*
X512425Y-432696D01*
Y-450196D01*
G01X524248D02*
X522938Y-449904D01*
X521628Y-448738D01*
X520754Y-446696D01*
X520318Y-444363D01*
X520754Y-442029D01*
X521628Y-439988D01*
X522938Y-438821D01*
X524248Y-438530D01*
X525558Y-438821D01*
X526868Y-439988D01*
X527741Y-442029D01*
X527960Y-444363D01*
X527741Y-446696D01*
X526868Y-448738D01*
X525558Y-449904D01*
X524248Y-450196D01*
G01X545678Y-432696D02*
Y-450196D01*
G01Y-447572D02*
X544805Y-449030D01*
X543494Y-449904D01*
X541966Y-450196D01*
X540220Y-449613D01*
X538910Y-448155D01*
X538036Y-446405D01*
X537818Y-444363D01*
X538036Y-442321D01*
X538910Y-440571D01*
X540220Y-439113D01*
X541966Y-438530D01*
X543494Y-438821D01*
X544586Y-439405D01*
X545678Y-440571D01*
G01X555973Y-442321D02*
X562960D01*
X562305Y-440279D01*
X561213Y-439113D01*
X559685Y-438530D01*
X558156Y-438821D01*
X556846Y-439696D01*
X555973Y-441738D01*
X555536Y-443488D01*
Y-445238D01*
X555973Y-446988D01*
X557065Y-448738D01*
X558375Y-449904D01*
X559903Y-450196D01*
X561431Y-449613D01*
X562960Y-447863D01*
G01X576748Y-450196D02*
Y-432696D01*
G01X754448Y-495196D02*
Y-477696D01*
X751828Y-481196D01*
G01Y-495196D02*
X757068D01*
G01X767800Y-487905D02*
X769328Y-485863D01*
X770638Y-484696D01*
X772385Y-484113D01*
X773913Y-484696D01*
X775005Y-485863D01*
X775878Y-487613D01*
X776096Y-489654D01*
X775878Y-491405D01*
X775005Y-493155D01*
X773694Y-494613D01*
X772166Y-495196D01*
X770420Y-494613D01*
X768891Y-492863D01*
X768018Y-490238D01*
X767800Y-487321D01*
X768236Y-483530D01*
X768891Y-481487D01*
X769983Y-479446D01*
X771511Y-477988D01*
X773040Y-477696D01*
X774568Y-478279D01*
X775660Y-479738D01*
G01X784645Y-491696D02*
X785954Y-493738D01*
X787701Y-494904D01*
X789666Y-495196D01*
X791413Y-494904D01*
X793160Y-493446D01*
X794251Y-491696D01*
X794470Y-489946D01*
X794033Y-487905D01*
X792505Y-486446D01*
X790976Y-485863D01*
X789011D01*
G01X790976D02*
X792286Y-484988D01*
X793378Y-483530D01*
X793815Y-481780D01*
X793378Y-480029D01*
X792286Y-478571D01*
X790321Y-477696D01*
X788356Y-477988D01*
X786391Y-479155D01*
G01X806948Y-495196D02*
Y-477696D01*
X804328Y-481196D01*
G01Y-495196D02*
X809568D01*
G01X819645Y-492572D02*
X820954Y-494030D01*
X822483Y-494904D01*
X824448Y-495196D01*
X826413Y-494613D01*
X827941Y-493446D01*
X829033Y-491405D01*
X829251Y-489071D01*
X828815Y-486738D01*
X827723Y-485279D01*
X826194Y-484113D01*
X824666Y-483821D01*
X823138Y-484113D01*
X821173Y-485279D01*
X821828Y-477696D01*
X827723D01*
G01X741331Y-450196D02*
Y-432696D01*
X746571D01*
X748318Y-433571D01*
X749628Y-435613D01*
X750065Y-437946D01*
X749628Y-440279D01*
X748536Y-442029D01*
X746571Y-442905D01*
X741331D01*
G01X768001Y-434155D02*
X766691Y-433279D01*
X765163Y-432696D01*
X763416D01*
X761451Y-433571D01*
X759923Y-435029D01*
X758831Y-436780D01*
X757958Y-439696D01*
X757739Y-442321D01*
X758176Y-444946D01*
X758831Y-446696D01*
X760141Y-448446D01*
X761670Y-449613D01*
X763198Y-450196D01*
X764726D01*
X766255Y-449613D01*
X767565Y-448738D01*
X768657Y-447572D01*
G01X782444Y-440863D02*
X783318Y-439988D01*
X783973Y-438530D01*
X784410Y-436487D01*
X783973Y-434738D01*
X783100Y-433571D01*
X781571Y-432696D01*
X775676D01*
Y-450196D01*
X782881D01*
X784410Y-449030D01*
X785283Y-447279D01*
X785720Y-445238D01*
X785283Y-443196D01*
X783973Y-441446D01*
X782444Y-440863D01*
X775676D01*
G01X791648Y-456029D02*
X804748D01*
G01X810676Y-450196D02*
Y-432696D01*
X820720Y-450196D01*
Y-432696D01*
G01X833198Y-450196D02*
X831451Y-449904D01*
X829923Y-448738D01*
X828613Y-446988D01*
X827739Y-444946D01*
X827303Y-442613D01*
Y-440279D01*
X827739Y-437946D01*
X828613Y-435904D01*
X829923Y-434155D01*
X831451Y-432988D01*
X833198Y-432696D01*
X834944Y-432988D01*
X836473Y-434155D01*
X837783Y-435904D01*
X838657Y-437946D01*
X839093Y-440279D01*
Y-442613D01*
X838657Y-444946D01*
X837783Y-446988D01*
X836473Y-448738D01*
X834944Y-449904D01*
X833198Y-450196D01*
G01X884039Y-432696D02*
X889498Y-450196D01*
X894957Y-432696D01*
G01X911365Y-450196D02*
X902631D01*
Y-432696D01*
X911365D01*
G01X907871Y-441154D02*
X902631D01*
G01X920131Y-450196D02*
Y-432696D01*
X925590D01*
X927336Y-433571D01*
X928428Y-434738D01*
X928865Y-437071D01*
X928428Y-439405D01*
X927118Y-440863D01*
X925590Y-441738D01*
X920131D01*
G01X925590D02*
X928865Y-450196D01*
G01X941998Y-450779D02*
X941561Y-450488D01*
Y-449904D01*
X941998Y-449613D01*
X942435Y-449904D01*
Y-450488D01*
X941998Y-450779D01*
G01X915748Y-495196D02*
Y-477696D01*
X913128Y-481196D01*
G01Y-495196D02*
X918368D01*
G01X1082981Y-432696D02*
Y-450196D01*
X1091715D01*
G01X1108778D02*
Y-438530D01*
G01Y-440571D02*
X1107905Y-439405D01*
X1106594Y-438821D01*
X1105066Y-438530D01*
X1103538Y-439113D01*
X1102228Y-440279D01*
X1101354Y-442029D01*
X1100918Y-444363D01*
X1101354Y-446696D01*
X1102228Y-448446D01*
X1103538Y-449613D01*
X1105066Y-450196D01*
X1106594Y-449904D01*
X1107905Y-449030D01*
X1108778Y-447863D01*
G01X1117763Y-455446D02*
X1119073Y-456029D01*
X1120820Y-455446D01*
X1121911Y-454280D01*
X1122785Y-452821D01*
X1124094Y-448155D01*
X1126933Y-438530D01*
G01X1119946D02*
X1124094Y-448155D01*
G01X1136573Y-442321D02*
X1143560D01*
X1142905Y-440279D01*
X1141813Y-439113D01*
X1140285Y-438530D01*
X1138756Y-438821D01*
X1137446Y-439696D01*
X1136573Y-441738D01*
X1136136Y-443488D01*
Y-445238D01*
X1136573Y-446988D01*
X1137665Y-448738D01*
X1138975Y-449904D01*
X1140503Y-450196D01*
X1142031Y-449613D01*
X1143560Y-447863D01*
G01X1154291Y-450196D02*
Y-438530D01*
G01Y-440863D02*
X1155383Y-439696D01*
X1156475Y-438821D01*
X1158003Y-438530D01*
X1159094Y-438821D01*
X1160405Y-439696D01*
G01X1109231Y-477696D02*
Y-495196D01*
X1117965D01*
G01X1126295Y-491696D02*
X1127604Y-493738D01*
X1129351Y-494904D01*
X1131316Y-495196D01*
X1133063Y-494904D01*
X1134810Y-493446D01*
X1135901Y-491696D01*
X1136120Y-489946D01*
X1135683Y-487905D01*
X1134155Y-486446D01*
X1132626Y-485863D01*
X1130661D01*
G01X1132626D02*
X1133936Y-484988D01*
X1135028Y-483530D01*
X1135465Y-481780D01*
X1135028Y-480029D01*
X1133936Y-478571D01*
X1131971Y-477696D01*
X1130006Y-477988D01*
X1128041Y-479155D01*
G01X1312898Y-495196D02*
X1311151Y-494904D01*
X1309623Y-493738D01*
X1308313Y-491988D01*
X1307439Y-489946D01*
X1307003Y-487613D01*
Y-485279D01*
X1307439Y-482946D01*
X1308313Y-480904D01*
X1309623Y-479155D01*
X1311151Y-477988D01*
X1312898Y-477696D01*
X1314644Y-477988D01*
X1316173Y-479155D01*
X1317483Y-480904D01*
X1318357Y-482946D01*
X1318793Y-485279D01*
Y-487613D01*
X1318357Y-489946D01*
X1317483Y-491988D01*
X1316173Y-493738D01*
X1314644Y-494904D01*
X1312898Y-495196D01*
G01X1314644Y-490529D02*
X1317265Y-495196D01*
G01X1325595Y-477696D02*
Y-490238D01*
X1326468Y-492863D01*
X1328215Y-494613D01*
X1330398Y-495196D01*
X1332581Y-494613D01*
X1334328Y-492863D01*
X1335201Y-490238D01*
Y-477696D01*
G01X1345278D02*
X1350518D01*
G01X1347898D02*
Y-495196D01*
G01X1345278D02*
X1350518D01*
G01X1360376D02*
Y-477696D01*
X1370420Y-495196D01*
Y-477696D01*
G01X1387701Y-479155D02*
X1386391Y-478279D01*
X1384863Y-477696D01*
X1383116D01*
X1381151Y-478571D01*
X1379623Y-480029D01*
X1378531Y-481780D01*
X1377658Y-484696D01*
X1377439Y-487321D01*
X1377876Y-489946D01*
X1378531Y-491696D01*
X1379841Y-493446D01*
X1381370Y-494613D01*
X1382898Y-495196D01*
X1384426D01*
X1385955Y-494613D01*
X1387265Y-493738D01*
X1388357Y-492572D01*
G01X1400398Y-495196D02*
Y-487321D01*
X1396031Y-477696D01*
G01X1404765D02*
X1400398Y-487321D01*
G01X1290595Y-450196D02*
Y-432696D01*
X1294961D01*
X1296708Y-433571D01*
X1298018Y-434738D01*
X1299110Y-436487D01*
X1299983Y-438530D01*
X1300201Y-441446D01*
X1299983Y-444363D01*
X1299110Y-446405D01*
X1298018Y-448155D01*
X1296708Y-449321D01*
X1294961Y-450196D01*
X1290595D01*
G01X1309623Y-442321D02*
X1316610D01*
X1315955Y-440279D01*
X1314863Y-439113D01*
X1313335Y-438530D01*
X1311806Y-438821D01*
X1310496Y-439696D01*
X1309623Y-441738D01*
X1309186Y-443488D01*
Y-445238D01*
X1309623Y-446988D01*
X1310715Y-448738D01*
X1312025Y-449904D01*
X1313553Y-450196D01*
X1315081Y-449613D01*
X1316610Y-447863D01*
G01X1327123Y-448155D02*
X1328215Y-449321D01*
X1329743Y-450196D01*
X1331053D01*
X1332363Y-449613D01*
X1333236Y-448738D01*
X1333673Y-447572D01*
X1333455Y-445821D01*
X1332581Y-444946D01*
X1328651Y-443196D01*
X1327778Y-441154D01*
X1328215Y-439696D01*
X1329088Y-438821D01*
X1330398Y-438530D01*
X1331708Y-438821D01*
X1333018Y-439696D01*
G01X1347898Y-438530D02*
Y-450196D01*
G01Y-433863D02*
X1347461Y-433571D01*
Y-432988D01*
X1347898Y-432696D01*
X1348335Y-432988D01*
Y-433571D01*
X1347898Y-433863D01*
G01X1362341Y-454571D02*
X1363870Y-455738D01*
X1365616Y-456029D01*
X1367144Y-455738D01*
X1368455Y-454280D01*
X1369328Y-452238D01*
Y-438530D01*
G01Y-440863D02*
X1368455Y-439696D01*
X1367144Y-438821D01*
X1365616Y-438530D01*
X1363870Y-439113D01*
X1362778Y-440279D01*
X1361904Y-442321D01*
X1361468Y-444363D01*
X1361686Y-446113D01*
X1362560Y-448155D01*
X1363870Y-449613D01*
X1365616Y-450196D01*
X1366926Y-449904D01*
X1368455Y-448738D01*
X1369328Y-447572D01*
G01X1379186Y-450196D02*
Y-438530D01*
G01Y-441446D02*
X1380060Y-439988D01*
X1381370Y-438821D01*
X1383116Y-438530D01*
X1384644Y-438821D01*
X1385955Y-439988D01*
X1386610Y-442029D01*
Y-450196D01*
G01X1397123Y-442321D02*
X1404110D01*
X1403455Y-440279D01*
X1402363Y-439113D01*
X1400835Y-438530D01*
X1399306Y-438821D01*
X1397996Y-439696D01*
X1397123Y-441738D01*
X1396686Y-443488D01*
Y-445238D01*
X1397123Y-446988D01*
X1398215Y-448738D01*
X1399525Y-449904D01*
X1401053Y-450196D01*
X1402581Y-449613D01*
X1404110Y-447863D01*
G01X1414841Y-450196D02*
Y-438530D01*
G01Y-440863D02*
X1415933Y-439696D01*
X1417025Y-438821D01*
X1418553Y-438530D01*
X1419644Y-438821D01*
X1420955Y-439696D01*
G01X1461598Y-477696D02*
X1459851Y-478279D01*
X1458541Y-479738D01*
X1457668Y-481487D01*
X1457013Y-483821D01*
X1456795Y-486446D01*
X1457013Y-489071D01*
X1457668Y-491405D01*
X1458541Y-493155D01*
X1459851Y-494613D01*
X1461598Y-495196D01*
X1463344Y-494613D01*
X1464655Y-493155D01*
X1465528Y-491405D01*
X1466183Y-489071D01*
X1466401Y-486446D01*
X1466183Y-483821D01*
X1465528Y-481487D01*
X1464655Y-479738D01*
X1463344Y-478279D01*
X1461598Y-477696D01*
G01X1474950Y-487905D02*
X1476478Y-485863D01*
X1477788Y-484696D01*
X1479535Y-484113D01*
X1481063Y-484696D01*
X1482155Y-485863D01*
X1483028Y-487613D01*
X1483246Y-489654D01*
X1483028Y-491405D01*
X1482155Y-493155D01*
X1480844Y-494613D01*
X1479316Y-495196D01*
X1477570Y-494613D01*
X1476041Y-492863D01*
X1475168Y-490238D01*
X1474950Y-487321D01*
X1475386Y-483530D01*
X1476041Y-481487D01*
X1477133Y-479446D01*
X1478661Y-477988D01*
X1480190Y-477696D01*
X1481718Y-478279D01*
X1482810Y-479738D01*
G01X1492668Y-495779D02*
X1500528Y-477696D01*
G01X1514098D02*
X1512351Y-478279D01*
X1511041Y-479738D01*
X1510168Y-481487D01*
X1509513Y-483821D01*
X1509295Y-486446D01*
X1509513Y-489071D01*
X1510168Y-491405D01*
X1511041Y-493155D01*
X1512351Y-494613D01*
X1514098Y-495196D01*
X1515844Y-494613D01*
X1517155Y-493155D01*
X1518028Y-491405D01*
X1518683Y-489071D01*
X1518901Y-486446D01*
X1518683Y-483821D01*
X1518028Y-481487D01*
X1517155Y-479738D01*
X1515844Y-478279D01*
X1514098Y-477696D01*
G01X1527886Y-493155D02*
X1529415Y-494613D01*
X1531161Y-495196D01*
X1532908Y-494613D01*
X1534436Y-492863D01*
X1535528Y-490238D01*
X1535965Y-487613D01*
Y-484405D01*
X1535528Y-481780D01*
X1534436Y-479446D01*
X1533126Y-478279D01*
X1531598Y-477696D01*
X1529851Y-478279D01*
X1528541Y-479446D01*
X1527668Y-481196D01*
X1527231Y-483530D01*
X1527668Y-485571D01*
X1528760Y-487613D01*
X1530070Y-488780D01*
X1531598Y-489071D01*
X1533344Y-488488D01*
X1534655Y-487029D01*
X1535965Y-484405D01*
G01X1545168Y-495779D02*
X1553028Y-477696D01*
G01X1562450Y-480613D02*
X1563760Y-478863D01*
X1565288Y-477988D01*
X1567035Y-477696D01*
X1569218Y-478279D01*
X1570746Y-479738D01*
X1571183Y-481487D01*
X1570965Y-483238D01*
X1570091Y-484696D01*
X1565725Y-487613D01*
X1563760Y-489654D01*
X1562450Y-492572D01*
X1562013Y-495196D01*
X1571183D01*
G01X1584098Y-477696D02*
X1582351Y-478279D01*
X1581041Y-479738D01*
X1580168Y-481487D01*
X1579513Y-483821D01*
X1579295Y-486446D01*
X1579513Y-489071D01*
X1580168Y-491405D01*
X1581041Y-493155D01*
X1582351Y-494613D01*
X1584098Y-495196D01*
X1585844Y-494613D01*
X1587155Y-493155D01*
X1588028Y-491405D01*
X1588683Y-489071D01*
X1588901Y-486446D01*
X1588683Y-483821D01*
X1588028Y-481487D01*
X1587155Y-479738D01*
X1585844Y-478279D01*
X1584098Y-477696D01*
G01X1601598Y-495196D02*
Y-477696D01*
X1598978Y-481196D01*
G01Y-495196D02*
X1604218D01*
G01X1618661D02*
X1619098Y-491405D01*
X1619753Y-488196D01*
X1620626Y-485279D01*
X1621718Y-482071D01*
X1623465Y-477696D01*
X1614731D01*
G01X1509295Y-450196D02*
Y-432696D01*
X1513661D01*
X1515408Y-433571D01*
X1516718Y-434738D01*
X1517810Y-436487D01*
X1518683Y-438530D01*
X1518901Y-441446D01*
X1518683Y-444363D01*
X1517810Y-446405D01*
X1516718Y-448155D01*
X1515408Y-449321D01*
X1513661Y-450196D01*
X1509295D01*
G01X1535528D02*
Y-438530D01*
G01Y-440571D02*
X1534655Y-439405D01*
X1533344Y-438821D01*
X1531816Y-438530D01*
X1530288Y-439113D01*
X1528978Y-440279D01*
X1528104Y-442029D01*
X1527668Y-444363D01*
X1528104Y-446696D01*
X1528978Y-448446D01*
X1530288Y-449613D01*
X1531816Y-450196D01*
X1533344Y-449904D01*
X1534655Y-449030D01*
X1535528Y-447863D01*
G01X1549098Y-432696D02*
Y-450196D01*
G01X1546041Y-438530D02*
X1552155D01*
G01X1563323Y-442321D02*
X1570310D01*
X1569655Y-440279D01*
X1568563Y-439113D01*
X1567035Y-438530D01*
X1565506Y-438821D01*
X1564196Y-439696D01*
X1563323Y-441738D01*
X1562886Y-443488D01*
Y-445238D01*
X1563323Y-446988D01*
X1564415Y-448738D01*
X1565725Y-449904D01*
X1567253Y-450196D01*
X1568781Y-449613D01*
X1570310Y-447863D01*
G54D19*
G01X536024Y114764D02*
Y116394D01*
X535473Y116945D01*
X532816D01*
X531855Y117906D01*
Y124285D01*
X533812Y128303D01*
X543279Y134566D01*
X563100Y138629D01*
X625675Y124986D01*
X661783Y132384D01*
X687543Y126768D01*
X708600Y131083D01*
X735420Y125236D01*
X763740Y131038D01*
X789208Y125484D01*
X815311Y130831D01*
X868565Y119221D01*
X927461Y131284D01*
X931398D01*
X935335Y135221D01*
X949114D01*
X950962Y137069D01*
Y139311D01*
X950716Y139803D01*
X949979Y140050D01*
X947047Y138583D01*
G01X536024Y120276D02*
Y118680D01*
X535439Y118095D01*
X533293D01*
X533005Y118383D01*
Y124019D01*
X534709Y127516D01*
X543728Y133484D01*
X563093Y137453D01*
X625668Y123810D01*
X661776Y131208D01*
X687536Y125592D01*
X708593Y129907D01*
X735413Y124060D01*
X763731Y129861D01*
X789201Y124308D01*
X815304Y129655D01*
X839516Y124377D01*
X868558Y118045D01*
X914646Y127485D01*
X915296Y127057D01*
X916912Y127388D01*
X917341Y128037D01*
X918957Y128368D01*
X919606Y127940D01*
X921223Y128271D01*
X921651Y128920D01*
X923267Y129251D01*
X923917Y128823D01*
X925533Y129154D01*
X925962Y129803D01*
X927578Y130134D01*
X931875D01*
X935812Y134071D01*
X949591D01*
X952112Y136592D01*
Y139583D01*
X951745Y140317D01*
X951990Y141054D01*
X954921Y142520D01*
M02*
